FILE_TYPE = MACRO_DRAWING;
SET COLOR_WIRE YELLOW;
SET COLOR_PROP MONO;
SET COLOR_DOT WHITE;
SET COLOR_ARC YELLOW;
SET COLOR_BODY GREEN;
SET COLOR_NOTE MONO;
SET PROP_DISPLAY VALUE;
SET PAGE_NUMBER P181;
FORCEADD CONN76_H22707001..1
(-625 3800);
FORCEPROP 2 LASTPIN (-125 2800) $PN I8
J 0
(-115 2810);
DISPLAY 0.617021 (-115 2810);
PAINT ORANGE (-115 2810);
FORCEPROP 2 LASTPIN (-125 2950) $PN F8
J 0
(-115 2960);
DISPLAY 0.617021 (-115 2960);
PAINT ORANGE (-115 2960);
FORCEPROP 1 LAST PART_NUMBER H22707-001
J 0
(-1075 2600);
DISPLAY 0.617021 (-1075 2600);
PAINT BLUE (-1075 2600);
FORCEPROP 2 LASTPIN (-125 4650) $PN C5
J 0
(-115 4660);
DISPLAY 0.617021 (-115 4660);
PAINT ORANGE (-115 4660);
FORCEPROP 2 LASTPIN (-125 4750) $PN A5
J 0
(-115 4760);
DISPLAY 0.617021 (-115 4760);
PAINT ORANGE (-115 4760);
FORCEPROP 2 LASTPIN (-125 4700) $PN B5
J 0
(-115 4710);
DISPLAY 0.617021 (-115 4710);
PAINT ORANGE (-115 4710);
FORCEPROP 2 LASTPIN (-125 4600) $PN D5
J 0
(-115 4610);
DISPLAY 0.617021 (-115 4610);
PAINT ORANGE (-115 4610);
FORCEPROP 2 LASTPIN (-125 4400) $PN H5
J 0
(-115 4410);
DISPLAY 0.617021 (-115 4410);
PAINT ORANGE (-115 4410);
FORCEPROP 2 LASTPIN (-125 4450) $PN G5
J 0
(-115 4460);
DISPLAY 0.617021 (-115 4460);
PAINT ORANGE (-115 4460);
FORCEPROP 2 LASTPIN (-125 4550) $PN E5
J 0
(-115 4560);
DISPLAY 0.617021 (-115 4560);
PAINT ORANGE (-115 4560);
FORCEPROP 2 LASTPIN (-125 4350) $PN I5
J 0
(-115 4360);
DISPLAY 0.617021 (-115 4360);
PAINT ORANGE (-115 4360);
FORCEPROP 2 LASTPIN (-125 4500) $PN F5
J 0
(-115 4510);
DISPLAY 0.617021 (-115 4510);
PAINT ORANGE (-115 4510);
FORCEPROP 2 LASTPIN (-125 4150) $PN C6
J 0
(-115 4160);
DISPLAY 0.617021 (-115 4160);
PAINT ORANGE (-115 4160);
FORCEPROP 2 LASTPIN (-125 4200) $PN B6
J 0
(-115 4210);
DISPLAY 0.617021 (-115 4210);
PAINT ORANGE (-115 4210);
FORCEPROP 2 LASTPIN (-125 4100) $PN D6
J 0
(-115 4110);
DISPLAY 0.617021 (-115 4110);
PAINT ORANGE (-115 4110);
FORCEPROP 2 LASTPIN (-125 4250) $PN A6
J 0
(-115 4260);
DISPLAY 0.617021 (-115 4260);
PAINT ORANGE (-115 4260);
FORCEPROP 1 LAST MATERIAL CONN
J 0
(-1075 5000);
DISPLAY 0.617021 (-1075 5000);
PAINT SKYBLUE (-1075 5000);
FORCEPROP 1 LAST LOCATION J1F1
J 0
(-1075 5050);
DISPLAY 0.617021 (-1075 5050);
PAINT AQUA (-1075 5050);
FORCEPROP 2 LASTPIN (-1125 4600) $PN D1
J 2
(-1135 4610);
DISPLAY 0.617021 (-1135 4610);
PAINT ORANGE (-1135 4610);
FORCEPROP 2 LASTPIN (-1125 4700) $PN B1
J 2
(-1135 4710);
DISPLAY 0.617021 (-1135 4710);
PAINT ORANGE (-1135 4710);
FORCEPROP 2 LASTPIN (-1125 4750) $PN A1
J 2
(-1135 4760);
DISPLAY 0.617021 (-1135 4760);
PAINT ORANGE (-1135 4760);
FORCEPROP 2 LASTPIN (-1125 4650) $PN C1
J 2
(-1135 4660);
DISPLAY 0.617021 (-1135 4660);
PAINT ORANGE (-1135 4660);
FORCEPROP 2 LASTPIN (-1125 4400) $PN H1
J 2
(-1135 4410);
DISPLAY 0.617021 (-1135 4410);
PAINT ORANGE (-1135 4410);
FORCEPROP 2 LASTPIN (-1125 4450) $PN G1
J 2
(-1135 4460);
DISPLAY 0.617021 (-1135 4460);
PAINT ORANGE (-1135 4460);
FORCEPROP 2 LASTPIN (-1125 4550) $PN E1
J 2
(-1135 4560);
DISPLAY 0.617021 (-1135 4560);
PAINT ORANGE (-1135 4560);
FORCEPROP 2 LASTPIN (-1125 4350) $PN I1
J 2
(-1135 4360);
DISPLAY 0.617021 (-1135 4360);
PAINT ORANGE (-1135 4360);
FORCEPROP 2 LASTPIN (-1125 4500) $PN F1
J 2
(-1135 4510);
DISPLAY 0.617021 (-1135 4510);
PAINT ORANGE (-1135 4510);
FORCEPROP 2 LASTPIN (-1125 4150) $PN C2
J 2
(-1135 4160);
DISPLAY 0.617021 (-1135 4160);
PAINT ORANGE (-1135 4160);
FORCEPROP 2 LASTPIN (-1125 4200) $PN B2
J 2
(-1135 4210);
DISPLAY 0.617021 (-1135 4210);
PAINT ORANGE (-1135 4210);
FORCEPROP 2 LASTPIN (-1125 4100) $PN D2
J 2
(-1135 4110);
DISPLAY 0.617021 (-1135 4110);
PAINT ORANGE (-1135 4110);
FORCEPROP 2 LASTPIN (-1125 4250) $PN A2
J 2
(-1135 4260);
DISPLAY 0.617021 (-1135 4260);
PAINT ORANGE (-1135 4260);
FORCEPROP 2 LASTPIN (-125 3950) $PN G6
J 0
(-115 3960);
DISPLAY 0.617021 (-115 3960);
PAINT ORANGE (-115 3960);
FORCEPROP 2 LASTPIN (-125 4050) $PN E6
J 0
(-115 4060);
DISPLAY 0.617021 (-115 4060);
PAINT ORANGE (-115 4060);
FORCEPROP 2 LASTPIN (-125 3850) $PN I6
J 0
(-115 3860);
DISPLAY 0.617021 (-115 3860);
PAINT ORANGE (-115 3860);
FORCEPROP 2 LASTPIN (-125 3900) $PN H6
J 0
(-115 3910);
DISPLAY 0.617021 (-115 3910);
PAINT ORANGE (-115 3910);
FORCEPROP 2 LASTPIN (-125 4000) $PN F6
J 0
(-115 4010);
DISPLAY 0.617021 (-115 4010);
PAINT ORANGE (-115 4010);
FORCEPROP 2 LASTPIN (-125 3650) $PN B7
J 0
(-115 3660);
DISPLAY 0.617021 (-115 3660);
PAINT ORANGE (-115 3660);
FORCEPROP 2 LASTPIN (-125 3700) $PN A7
J 0
(-115 3710);
DISPLAY 0.617021 (-115 3710);
PAINT ORANGE (-115 3710);
FORCEPROP 2 LASTPIN (-125 3800) $PN J6
J 0
(-115 3810);
DISPLAY 0.617021 (-115 3810);
PAINT ORANGE (-115 3810);
FORCEPROP 2 LASTPIN (-125 3600) $PN C7
J 0
(-115 3610);
DISPLAY 0.617021 (-115 3610);
PAINT ORANGE (-115 3610);
FORCEPROP 2 LASTPIN (-125 3550) $PN D7
J 0
(-115 3560);
DISPLAY 0.617021 (-115 3560);
PAINT ORANGE (-115 3560);
FORCEPROP 2 LASTPIN (-125 3350) $PN H7
J 0
(-115 3360);
DISPLAY 0.617021 (-115 3360);
PAINT ORANGE (-115 3360);
FORCEPROP 2 LASTPIN (-125 3400) $PN G7
J 0
(-115 3410);
DISPLAY 0.617021 (-115 3410);
PAINT ORANGE (-115 3410);
FORCEPROP 2 LASTPIN (-125 3500) $PN E7
J 0
(-115 3510);
DISPLAY 0.617021 (-115 3510);
PAINT ORANGE (-115 3510);
FORCEPROP 2 LASTPIN (-125 3450) $PN F7
J 0
(-115 3460);
DISPLAY 0.617021 (-115 3460);
PAINT ORANGE (-115 3460);
FORCEPROP 2 LASTPIN (-125 3300) $PN I7
J 0
(-115 3310);
DISPLAY 0.617021 (-115 3310);
PAINT ORANGE (-115 3310);
FORCEPROP 2 LASTPIN (-125 3100) $PN C8
J 0
(-115 3110);
DISPLAY 0.617021 (-115 3110);
PAINT ORANGE (-115 3110);
FORCEPROP 2 LASTPIN (-125 3150) $PN B8
J 0
(-115 3160);
DISPLAY 0.617021 (-115 3160);
PAINT ORANGE (-115 3160);
FORCEPROP 2 LASTPIN (-125 3200) $PN A8
J 0
(-115 3210);
DISPLAY 0.617021 (-115 3210);
PAINT ORANGE (-115 3210);
FORCEPROP 2 LASTPIN (-125 3050) $PN D8
J 0
(-115 3060);
DISPLAY 0.617021 (-115 3060);
PAINT ORANGE (-115 3060);
FORCEPROP 2 LASTPIN (-125 2850) $PN H8
J 0
(-115 2860);
DISPLAY 0.617021 (-115 2860);
PAINT ORANGE (-115 2860);
FORCEPROP 2 LASTPIN (-125 3000) $PN E8
J 0
(-115 3010);
DISPLAY 0.617021 (-115 3010);
PAINT ORANGE (-115 3010);
FORCEPROP 2 LASTPIN (-125 2900) $PN G8
J 0
(-115 2910);
DISPLAY 0.617021 (-115 2910);
PAINT ORANGE (-115 2910);
FORCEPROP 2 LASTPIN (-125 2750) $PN J8
J 0
(-115 2760);
DISPLAY 0.617021 (-115 2760);
PAINT ORANGE (-115 2760);
FORCEPROP 2 LASTPIN (-1125 3850) $PN I2
J 2
(-1135 3860);
DISPLAY 0.617021 (-1135 3860);
PAINT ORANGE (-1135 3860);
FORCEPROP 2 LASTPIN (-1125 3900) $PN H2
J 2
(-1135 3910);
DISPLAY 0.617021 (-1135 3910);
PAINT ORANGE (-1135 3910);
FORCEPROP 2 LASTPIN (-1125 4000) $PN F2
J 2
(-1135 4010);
DISPLAY 0.617021 (-1135 4010);
PAINT ORANGE (-1135 4010);
FORCEPROP 2 LASTPIN (-1125 4050) $PN E2
J 2
(-1135 4060);
DISPLAY 0.617021 (-1135 4060);
PAINT ORANGE (-1135 4060);
FORCEPROP 2 LASTPIN (-1125 3950) $PN G2
J 2
(-1135 3960);
DISPLAY 0.617021 (-1135 3960);
PAINT ORANGE (-1135 3960);
FORCEPROP 2 LASTPIN (-1125 3600) $PN C3
J 2
(-1135 3610);
DISPLAY 0.617021 (-1135 3610);
PAINT ORANGE (-1135 3610);
FORCEPROP 2 LASTPIN (-1125 3800) $PN J2
J 2
(-1135 3810);
DISPLAY 0.617021 (-1135 3810);
PAINT ORANGE (-1135 3810);
FORCEPROP 2 LASTPIN (-1125 3700) $PN A3
J 2
(-1135 3710);
DISPLAY 0.617021 (-1135 3710);
PAINT ORANGE (-1135 3710);
FORCEPROP 2 LASTPIN (-1125 3650) $PN B3
J 2
(-1135 3660);
DISPLAY 0.617021 (-1135 3660);
PAINT ORANGE (-1135 3660);
FORCEPROP 2 LASTPIN (-1125 3550) $PN D3
J 2
(-1135 3560);
DISPLAY 0.617021 (-1135 3560);
PAINT ORANGE (-1135 3560);
FORCEPROP 2 LASTPIN (-1125 3350) $PN H3
J 2
(-1135 3360);
DISPLAY 0.617021 (-1135 3360);
PAINT ORANGE (-1135 3360);
FORCEPROP 2 LASTPIN (-1125 3400) $PN G3
J 2
(-1135 3410);
DISPLAY 0.617021 (-1135 3410);
PAINT ORANGE (-1135 3410);
FORCEPROP 2 LASTPIN (-1125 3500) $PN E3
J 2
(-1135 3510);
DISPLAY 0.617021 (-1135 3510);
PAINT ORANGE (-1135 3510);
FORCEPROP 2 LASTPIN (-1125 3450) $PN F3
J 2
(-1135 3460);
DISPLAY 0.617021 (-1135 3460);
PAINT ORANGE (-1135 3460);
FORCEPROP 2 LASTPIN (-1125 3300) $PN I3
J 2
(-1135 3310);
DISPLAY 0.617021 (-1135 3310);
PAINT ORANGE (-1135 3310);
FORCEPROP 2 LASTPIN (-1125 3200) $PN A4
J 2
(-1135 3210);
DISPLAY 0.617021 (-1135 3210);
PAINT ORANGE (-1135 3210);
FORCEPROP 2 LASTPIN (-1125 3150) $PN B4
J 2
(-1135 3160);
DISPLAY 0.617021 (-1135 3160);
PAINT ORANGE (-1135 3160);
FORCEPROP 2 LASTPIN (-1125 3100) $PN C4
J 2
(-1135 3110);
DISPLAY 0.617021 (-1135 3110);
PAINT ORANGE (-1135 3110);
FORCEPROP 2 LASTPIN (-1125 3050) $PN D4
J 2
(-1135 3060);
DISPLAY 0.617021 (-1135 3060);
PAINT ORANGE (-1135 3060);
FORCEPROP 2 LASTPIN (-1125 3000) $PN E4
J 2
(-1135 3010);
DISPLAY 0.617021 (-1135 3010);
PAINT ORANGE (-1135 3010);
FORCEPROP 2 LASTPIN (-1125 2900) $PN G4
J 2
(-1135 2910);
DISPLAY 0.617021 (-1135 2910);
PAINT ORANGE (-1135 2910);
FORCEPROP 2 LASTPIN (-1125 2950) $PN F4
J 2
(-1135 2960);
DISPLAY 0.617021 (-1135 2960);
PAINT ORANGE (-1135 2960);
FORCEPROP 2 LASTPIN (-1125 2850) $PN H4
J 2
(-1135 2860);
DISPLAY 0.617021 (-1135 2860);
PAINT ORANGE (-1135 2860);
FORCEPROP 2 LASTPIN (-1125 2800) $PN I4
J 2
(-1135 2810);
DISPLAY 0.617021 (-1135 2810);
PAINT ORANGE (-1135 2810);
FORCEPROP 2 LASTPIN (-1125 2750) $PN J4
J 2
(-1135 2760);
DISPLAY 0.617021 (-1135 2760);
PAINT ORANGE (-1135 2760);
FORCEPROP 1 LAST PATH I111
J 0
(-550 5000);
PAINT GREEN (-550 5000);
DISPLAY INVISIBLE (-550 5000);
FORCEPROP 0 LAST BOM_COST IO_SLOT
J 0
(-1075 5250);
DISPLAY 1.021277 (-1075 5250);
PAINT ORANGE (-1075 5250);
DISPLAY INVISIBLE (-1075 5250);
FORCEPROP 0 LAST ROOM IO_SLOT
J 0
(-1075 5150);
DISPLAY 1.021277 (-1075 5150);
PAINT ORANGE (-1075 5150);
DISPLAY INVISIBLE (-1075 5150);
FORCEPROP 2 LAST SEC 1
J 0
(-1075 5100);
DISPLAY 0.680851 (-1075 5100);
PAINT MONO (-1075 5100);
DISPLAY INVISIBLE (-1075 5100);
FORCEPROP 2 LAST SEC_TYPE THMT1
J 0
(-1075 5100);
DISPLAY 1.021277 (-1075 5100);
PAINT ORANGE (-1075 5100);
DISPLAY INVISIBLE (-1075 5100);
FORCEPROP 1 LAST PACK_TYPE THMT1
J 0
(-1075 5100);
PAINT SKYBLUE (-1075 5100);
DISPLAY INVISIBLE (-1075 5100);
FORCEPROP 2 LAST CDS_LOCATION J1F1
J 0
(-1075 5050);
DISPLAY 0.617021 (-1075 5050);
PAINT AQUA (-1075 5050);
DISPLAY INVISIBLE (-1075 5050);
FORCEPROP 2 LAST CDS_LIB mstr_conn
J 0
(-625 3800);
PAINT ORANGE (-625 3800);
DISPLAY INVISIBLE (-625 3800);
FORCEADD GND..1
(-1350 2425);
FORCEPROP 3 LASTPIN (-1350 2475) SIG_NAME GND\g
J 0
(-1340 2485);
DISPLAY 0.659574 (-1340 2485);
PAINT MONO (-1340 2485);
DISPLAY INVISIBLE (-1340 2485);
FORCEPROP 1 LAST HDL_POWER GND
J 0
(-1350 2575);
DISPLAY 0.872340 (-1350 2575);
PAINT GREEN (-1350 2575);
DISPLAY INVISIBLE (-1350 2575);
FORCEPROP 1 LAST SIZE 1B
J 0
(-1275 2375);
DISPLAY 0.872340 (-1275 2375);
PAINT GREEN (-1275 2375);
DISPLAY INVISIBLE (-1275 2375);
FORCEPROP 1 LAST PATH I112
J 0
(-1275 2425);
DISPLAY 0.872340 (-1275 2425);
PAINT AQUA (-1275 2425);
DISPLAY INVISIBLE (-1275 2425);
FORCEPROP 1 LAST VOLTAGE 0
J 0
(-1350 2425);
PAINT SKYBLUE (-1350 2425);
DISPLAY INVISIBLE (-1350 2425);
FORCEPROP 2 LAST CDS_LIB mstr_symbols
J 0
(-1350 2425);
PAINT ORANGE (-1350 2425);
DISPLAY INVISIBLE (-1350 2425);
FORCEPROP 1 LAST BODY_TYPE PLUMBING
J 0
(-1395 2382);
DISPLAY 0.340426 (-1395 2382);
PAINT GREEN (-1395 2382);
DISPLAY INVISIBLE (-1395 2382);
FORCEPROP 2 LAST ROOM P2V5_LAN_AUX_VR
J 0
(-1650 2500);
DISPLAY 0.617021 (-1650 2500);
PAINT ORANGE (-1650 2500);
DISPLAY INVISIBLE (-1650 2500);
FORCEPROP 2 LAST BOM_COST NT_BASE_VRD
J 0
(-1650 2500);
DISPLAY 0.617021 (-1650 2500);
PAINT ORANGE (-1650 2500);
DISPLAY INVISIBLE (-1650 2500);
FORCEADD TAP..1
R 2
(-1600 4450);
FORCEPROP 3 LASTPIN (-1550 4450) SIG_NAME P3E_CPU1_PE3_MP_RXP<2>
J 0
(-1540 4460);
DISPLAY 0.659574 (-1540 4460);
PAINT MONO (-1540 4460);
DISPLAY INVISIBLE (-1540 4460);
FORCEPROP 1 LASTPIN (-1550 4450) BN 2
J 2
(-1538 4458);
DISPLAY 0.617021 (-1538 4458);
PAINT GREEN (-1538 4458);
FORCEPROP 1 LAST BODY_TYPE PLUMBING
J 2
(-1600 4500);
DISPLAY 1.446809 (-1600 4500);
PAINT GREEN (-1600 4500);
DISPLAY INVISIBLE (-1600 4500);
FORCEPROP 1 LAST PATH I113
J 2
(-1598 4450);
DISPLAY 0.872340 (-1598 4450);
PAINT GREEN (-1598 4450);
DISPLAY INVISIBLE (-1598 4450);
FORCEPROP 2 LAST CDS_LIB mstr_standard
J 0
(-1600 4450);
PAINT ORANGE (-1600 4450);
DISPLAY INVISIBLE (-1600 4450);
FORCEPROP 1 LAST HDL_TAP TRUE
J 2
(-1925 4325);
DISPLAY 1.446809 (-1925 4325);
PAINT GREEN (-1925 4325);
DISPLAY INVISIBLE (-1925 4325);
FORCEADD TAP..1
R 2
(-1850 4400);
FORCEPROP 3 LASTPIN (-1800 4400) SIG_NAME P3E_CPU1_PE3_MP_RXN<2>
J 0
(-1790 4410);
DISPLAY 0.659574 (-1790 4410);
PAINT MONO (-1790 4410);
DISPLAY INVISIBLE (-1790 4410);
FORCEPROP 1 LASTPIN (-1800 4400) BN 2
J 2
(-1788 4408);
DISPLAY 0.617021 (-1788 4408);
PAINT GREEN (-1788 4408);
FORCEPROP 1 LAST PATH I114
J 2
(-1848 4400);
DISPLAY 0.872340 (-1848 4400);
PAINT GREEN (-1848 4400);
DISPLAY INVISIBLE (-1848 4400);
FORCEPROP 1 LAST BODY_TYPE PLUMBING
J 2
(-1850 4450);
DISPLAY 1.446809 (-1850 4450);
PAINT GREEN (-1850 4450);
DISPLAY INVISIBLE (-1850 4450);
FORCEPROP 2 LAST CDS_LIB mstr_standard
J 0
(-1850 4400);
PAINT ORANGE (-1850 4400);
DISPLAY INVISIBLE (-1850 4400);
FORCEPROP 1 LAST HDL_TAP TRUE
J 2
(-2175 4275);
DISPLAY 1.446809 (-2175 4275);
PAINT GREEN (-2175 4275);
DISPLAY INVISIBLE (-2175 4275);
FORCEADD TAP..1
R 2
(-1600 3900);
FORCEPROP 3 LASTPIN (-1550 3900) SIG_NAME P3E_CPU1_PE3_MP_RXP<5>
J 0
(-1540 3910);
DISPLAY 0.659574 (-1540 3910);
PAINT MONO (-1540 3910);
DISPLAY INVISIBLE (-1540 3910);
FORCEPROP 1 LASTPIN (-1550 3900) BN 5
J 2
(-1538 3908);
DISPLAY 0.617021 (-1538 3908);
PAINT GREEN (-1538 3908);
FORCEPROP 1 LAST BODY_TYPE PLUMBING
J 2
(-1600 3950);
DISPLAY 1.446809 (-1600 3950);
PAINT GREEN (-1600 3950);
DISPLAY INVISIBLE (-1600 3950);
FORCEPROP 1 LAST PATH I115
J 2
(-1598 3900);
DISPLAY 0.872340 (-1598 3900);
PAINT GREEN (-1598 3900);
DISPLAY INVISIBLE (-1598 3900);
FORCEPROP 2 LAST CDS_LIB mstr_standard
J 0
(-1600 3900);
PAINT ORANGE (-1600 3900);
DISPLAY INVISIBLE (-1600 3900);
FORCEPROP 1 LAST HDL_TAP TRUE
J 2
(-1925 3775);
DISPLAY 1.446809 (-1925 3775);
PAINT GREEN (-1925 3775);
DISPLAY INVISIBLE (-1925 3775);
FORCEADD TAP..1
R 2
(-1850 3850);
FORCEPROP 3 LASTPIN (-1800 3850) SIG_NAME P3E_CPU1_PE3_MP_RXN<5>
J 0
(-1790 3860);
DISPLAY 0.659574 (-1790 3860);
PAINT MONO (-1790 3860);
DISPLAY INVISIBLE (-1790 3860);
FORCEPROP 1 LASTPIN (-1800 3850) BN 5
J 2
(-1788 3858);
DISPLAY 0.617021 (-1788 3858);
PAINT GREEN (-1788 3858);
FORCEPROP 2 LAST CDS_LIB mstr_standard
J 0
(-1850 3850);
PAINT ORANGE (-1850 3850);
DISPLAY INVISIBLE (-1850 3850);
FORCEPROP 1 LAST PATH I116
J 2
(-1848 3850);
DISPLAY 0.872340 (-1848 3850);
PAINT GREEN (-1848 3850);
DISPLAY INVISIBLE (-1848 3850);
FORCEPROP 1 LAST BODY_TYPE PLUMBING
J 2
(-1850 3900);
DISPLAY 1.446809 (-1850 3900);
PAINT GREEN (-1850 3900);
DISPLAY INVISIBLE (-1850 3900);
FORCEPROP 1 LAST HDL_TAP TRUE
J 2
(-2175 3725);
DISPLAY 1.446809 (-2175 3725);
PAINT GREEN (-2175 3725);
DISPLAY INVISIBLE (-2175 3725);
FORCEADD TAP..6
R 2
(1700 3100);
FORCEPROP 3 LASTPIN (1650 3100) SIG_NAME P3E_CPU1_PE3_MP_TXP<0>
J 0
(1660 3110);
DISPLAY 0.659574 (1660 3110);
PAINT MONO (1660 3110);
DISPLAY INVISIBLE (1660 3110);
FORCEPROP 1 LASTPIN (1650 3100) BN 0
J 2
(1702 3108);
DISPLAY 0.617021 (1702 3108);
PAINT GREEN (1702 3108);
FORCEPROP 1 LAST PATH I117
J 2
(1702 3100);
DISPLAY 0.872340 (1702 3100);
PAINT GREEN (1702 3100);
DISPLAY INVISIBLE (1702 3100);
FORCEPROP 2 LAST CDS_LIB mstr_standard
J 0
(1700 3100);
PAINT ORANGE (1700 3100);
DISPLAY INVISIBLE (1700 3100);
FORCEPROP 1 LAST BODY_TYPE PLUMBING
J 2
(1700 3050);
DISPLAY 1.234043 (1700 3050);
PAINT GREEN (1700 3050);
DISPLAY INVISIBLE (1700 3050);
FORCEPROP 1 LAST HDL_TAP TRUE
J 2
(1375 2975);
DISPLAY 1.234043 (1375 2975);
PAINT GREEN (1375 2975);
DISPLAY INVISIBLE (1375 2975);
FORCEADD TAP..6
R 2
(1950 3150);
FORCEPROP 3 LASTPIN (1900 3150) SIG_NAME P3E_CPU1_PE3_MP_TXN<0>
J 0
(1910 3160);
DISPLAY 0.659574 (1910 3160);
PAINT MONO (1910 3160);
DISPLAY INVISIBLE (1910 3160);
FORCEPROP 1 LASTPIN (1900 3150) BN 0
J 2
(1952 3158);
DISPLAY 0.617021 (1952 3158);
PAINT GREEN (1952 3158);
FORCEPROP 1 LAST PATH I118
J 2
(1952 3150);
DISPLAY 0.872340 (1952 3150);
PAINT GREEN (1952 3150);
DISPLAY INVISIBLE (1952 3150);
FORCEPROP 1 LAST BODY_TYPE PLUMBING
J 2
(1950 3100);
DISPLAY 1.234043 (1950 3100);
PAINT GREEN (1950 3100);
DISPLAY INVISIBLE (1950 3100);
FORCEPROP 2 LAST CDS_LIB mstr_standard
J 0
(1950 3150);
PAINT ORANGE (1950 3150);
DISPLAY INVISIBLE (1950 3150);
FORCEPROP 1 LAST HDL_TAP TRUE
J 2
(1625 3025);
DISPLAY 1.234043 (1625 3025);
PAINT GREEN (1625 3025);
DISPLAY INVISIBLE (1625 3025);
FORCEADD TAP..6
R 2
(1700 2950);
FORCEPROP 3 LASTPIN (1650 2950) SIG_NAME P3E_CPU1_PE3_MP_TXP<1>
J 0
(1660 2960);
DISPLAY 0.659574 (1660 2960);
PAINT MONO (1660 2960);
DISPLAY INVISIBLE (1660 2960);
FORCEPROP 1 LASTPIN (1650 2950) BN 1
J 2
(1702 2958);
DISPLAY 0.617021 (1702 2958);
PAINT GREEN (1702 2958);
FORCEPROP 2 LAST CDS_LIB mstr_standard
J 0
(1700 2950);
PAINT ORANGE (1700 2950);
DISPLAY INVISIBLE (1700 2950);
FORCEPROP 1 LAST BODY_TYPE PLUMBING
J 2
(1700 2900);
DISPLAY 1.234043 (1700 2900);
PAINT GREEN (1700 2900);
DISPLAY INVISIBLE (1700 2900);
FORCEPROP 1 LAST PATH I119
J 2
(1702 2950);
DISPLAY 0.872340 (1702 2950);
PAINT GREEN (1702 2950);
DISPLAY INVISIBLE (1702 2950);
FORCEPROP 1 LAST HDL_TAP TRUE
J 2
(1375 2825);
DISPLAY 1.234043 (1375 2825);
PAINT GREEN (1375 2825);
DISPLAY INVISIBLE (1375 2825);
FORCEADD TAP..6
R 2
(1950 3000);
FORCEPROP 3 LASTPIN (1900 3000) SIG_NAME P3E_CPU1_PE3_MP_TXN<1>
J 0
(1910 3010);
DISPLAY 0.659574 (1910 3010);
PAINT MONO (1910 3010);
DISPLAY INVISIBLE (1910 3010);
FORCEPROP 1 LASTPIN (1900 3000) BN 1
J 2
(1952 3008);
DISPLAY 0.617021 (1952 3008);
PAINT GREEN (1952 3008);
FORCEPROP 2 LAST CDS_LIB mstr_standard
J 0
(1950 3000);
PAINT ORANGE (1950 3000);
DISPLAY INVISIBLE (1950 3000);
FORCEPROP 1 LAST BODY_TYPE PLUMBING
J 2
(1950 2950);
DISPLAY 1.234043 (1950 2950);
PAINT GREEN (1950 2950);
DISPLAY INVISIBLE (1950 2950);
FORCEPROP 1 LAST PATH I120
J 2
(1952 3000);
DISPLAY 0.872340 (1952 3000);
PAINT GREEN (1952 3000);
DISPLAY INVISIBLE (1952 3000);
FORCEPROP 1 LAST HDL_TAP TRUE
J 2
(1625 2875);
DISPLAY 1.234043 (1625 2875);
PAINT GREEN (1625 2875);
DISPLAY INVISIBLE (1625 2875);
FORCEADD TAP..6
R 2
(1950 2850);
FORCEPROP 3 LASTPIN (1900 2850) SIG_NAME P3E_CPU1_PE3_MP_TXN<2>
J 0
(1910 2860);
DISPLAY 0.659574 (1910 2860);
PAINT MONO (1910 2860);
DISPLAY INVISIBLE (1910 2860);
FORCEPROP 1 LASTPIN (1900 2850) BN 2
J 2
(1952 2858);
DISPLAY 0.617021 (1952 2858);
PAINT GREEN (1952 2858);
FORCEPROP 2 LAST CDS_LIB mstr_standard
J 0
(1950 2850);
PAINT ORANGE (1950 2850);
DISPLAY INVISIBLE (1950 2850);
FORCEPROP 1 LAST PATH I121
J 2
(1952 2850);
DISPLAY 0.872340 (1952 2850);
PAINT GREEN (1952 2850);
DISPLAY INVISIBLE (1952 2850);
FORCEPROP 1 LAST BODY_TYPE PLUMBING
J 2
(1950 2800);
DISPLAY 1.234043 (1950 2800);
PAINT GREEN (1950 2800);
DISPLAY INVISIBLE (1950 2800);
FORCEPROP 1 LAST HDL_TAP TRUE
J 2
(1625 2725);
DISPLAY 1.234043 (1625 2725);
PAINT GREEN (1625 2725);
DISPLAY INVISIBLE (1625 2725);
FORCEADD TAP..6
R 2
(1700 2800);
FORCEPROP 3 LASTPIN (1650 2800) SIG_NAME P3E_CPU1_PE3_MP_TXP<2>
J 0
(1660 2810);
DISPLAY 0.659574 (1660 2810);
PAINT MONO (1660 2810);
DISPLAY INVISIBLE (1660 2810);
FORCEPROP 1 LASTPIN (1650 2800) BN 2
J 2
(1702 2808);
DISPLAY 0.617021 (1702 2808);
PAINT GREEN (1702 2808);
FORCEPROP 2 LAST CDS_LIB mstr_standard
J 0
(1700 2800);
PAINT ORANGE (1700 2800);
DISPLAY INVISIBLE (1700 2800);
FORCEPROP 1 LAST PATH I122
J 2
(1702 2800);
DISPLAY 0.872340 (1702 2800);
PAINT GREEN (1702 2800);
DISPLAY INVISIBLE (1702 2800);
FORCEPROP 1 LAST BODY_TYPE PLUMBING
J 2
(1700 2750);
DISPLAY 1.234043 (1700 2750);
PAINT GREEN (1700 2750);
DISPLAY INVISIBLE (1700 2750);
FORCEPROP 1 LAST HDL_TAP TRUE
J 2
(1375 2675);
DISPLAY 1.234043 (1375 2675);
PAINT GREEN (1375 2675);
DISPLAY INVISIBLE (1375 2675);
FORCEADD TAP..6
R 2
(1950 3700);
FORCEPROP 3 LASTPIN (1900 3700) SIG_NAME P3E_CPU1_PE3_MP_TXN<3>
J 0
(1910 3710);
DISPLAY 0.659574 (1910 3710);
PAINT MONO (1910 3710);
DISPLAY INVISIBLE (1910 3710);
FORCEPROP 1 LASTPIN (1900 3700) BN 3
J 2
(1952 3708);
DISPLAY 0.617021 (1952 3708);
PAINT GREEN (1952 3708);
FORCEPROP 1 LAST PATH I123
J 2
(1952 3700);
DISPLAY 0.872340 (1952 3700);
PAINT GREEN (1952 3700);
DISPLAY INVISIBLE (1952 3700);
FORCEPROP 1 LAST BODY_TYPE PLUMBING
J 2
(1950 3650);
DISPLAY 1.234043 (1950 3650);
PAINT GREEN (1950 3650);
DISPLAY INVISIBLE (1950 3650);
FORCEPROP 2 LAST CDS_LIB mstr_standard
J 0
(1950 3700);
PAINT ORANGE (1950 3700);
DISPLAY INVISIBLE (1950 3700);
FORCEPROP 1 LAST HDL_TAP TRUE
J 2
(1625 3575);
DISPLAY 1.234043 (1625 3575);
PAINT GREEN (1625 3575);
DISPLAY INVISIBLE (1625 3575);
FORCEADD TAP..6
R 2
(1700 3650);
FORCEPROP 3 LASTPIN (1650 3650) SIG_NAME P3E_CPU1_PE3_MP_TXP<3>
J 0
(1660 3660);
DISPLAY 0.659574 (1660 3660);
PAINT MONO (1660 3660);
DISPLAY INVISIBLE (1660 3660);
FORCEPROP 1 LASTPIN (1650 3650) BN 3
J 2
(1702 3658);
DISPLAY 0.617021 (1702 3658);
PAINT GREEN (1702 3658);
FORCEPROP 1 LAST PATH I124
J 2
(1702 3650);
DISPLAY 0.872340 (1702 3650);
PAINT GREEN (1702 3650);
DISPLAY INVISIBLE (1702 3650);
FORCEPROP 1 LAST BODY_TYPE PLUMBING
J 2
(1700 3600);
DISPLAY 1.234043 (1700 3600);
PAINT GREEN (1700 3600);
DISPLAY INVISIBLE (1700 3600);
FORCEPROP 2 LAST CDS_LIB mstr_standard
J 0
(1700 3650);
PAINT ORANGE (1700 3650);
DISPLAY INVISIBLE (1700 3650);
FORCEPROP 1 LAST HDL_TAP TRUE
J 2
(1375 3525);
DISPLAY 1.234043 (1375 3525);
PAINT GREEN (1375 3525);
DISPLAY INVISIBLE (1375 3525);
FORCEADD TAP..6
R 2
(1950 3550);
FORCEPROP 3 LASTPIN (1900 3550) SIG_NAME P3E_CPU1_PE3_MP_TXN<4>
J 0
(1910 3560);
DISPLAY 0.659574 (1910 3560);
PAINT MONO (1910 3560);
DISPLAY INVISIBLE (1910 3560);
FORCEPROP 1 LASTPIN (1900 3550) BN 4
J 2
(1952 3558);
DISPLAY 0.617021 (1952 3558);
PAINT GREEN (1952 3558);
FORCEPROP 1 LAST PATH I125
J 2
(1952 3550);
DISPLAY 0.872340 (1952 3550);
PAINT GREEN (1952 3550);
DISPLAY INVISIBLE (1952 3550);
FORCEPROP 2 LAST CDS_LIB mstr_standard
J 0
(1950 3550);
PAINT ORANGE (1950 3550);
DISPLAY INVISIBLE (1950 3550);
FORCEPROP 1 LAST BODY_TYPE PLUMBING
J 2
(1950 3500);
DISPLAY 1.234043 (1950 3500);
PAINT GREEN (1950 3500);
DISPLAY INVISIBLE (1950 3500);
FORCEPROP 1 LAST HDL_TAP TRUE
J 2
(1625 3425);
DISPLAY 1.234043 (1625 3425);
PAINT GREEN (1625 3425);
DISPLAY INVISIBLE (1625 3425);
FORCEADD TAP..6
R 2
(1700 3500);
FORCEPROP 3 LASTPIN (1650 3500) SIG_NAME P3E_CPU1_PE3_MP_TXP<4>
J 0
(1660 3510);
DISPLAY 0.659574 (1660 3510);
PAINT MONO (1660 3510);
DISPLAY INVISIBLE (1660 3510);
FORCEPROP 1 LASTPIN (1650 3500) BN 4
J 2
(1702 3508);
DISPLAY 0.617021 (1702 3508);
PAINT GREEN (1702 3508);
FORCEPROP 2 LAST CDS_LIB mstr_standard
J 0
(1700 3500);
PAINT ORANGE (1700 3500);
DISPLAY INVISIBLE (1700 3500);
FORCEPROP 1 LAST PATH I126
J 2
(1702 3500);
DISPLAY 0.872340 (1702 3500);
PAINT GREEN (1702 3500);
DISPLAY INVISIBLE (1702 3500);
FORCEPROP 1 LAST BODY_TYPE PLUMBING
J 2
(1700 3450);
DISPLAY 1.234043 (1700 3450);
PAINT GREEN (1700 3450);
DISPLAY INVISIBLE (1700 3450);
FORCEPROP 1 LAST HDL_TAP TRUE
J 2
(1375 3375);
DISPLAY 1.234043 (1375 3375);
PAINT GREEN (1375 3375);
DISPLAY INVISIBLE (1375 3375);
FORCEADD TAP..6
R 2
(1950 3350);
FORCEPROP 3 LASTPIN (1900 3350) SIG_NAME P3E_CPU1_PE3_MP_TXN<5>
J 0
(1910 3360);
DISPLAY 0.659574 (1910 3360);
PAINT MONO (1910 3360);
DISPLAY INVISIBLE (1910 3360);
FORCEPROP 1 LASTPIN (1900 3350) BN 5
J 2
(1952 3358);
DISPLAY 0.617021 (1952 3358);
PAINT GREEN (1952 3358);
FORCEPROP 2 LAST CDS_LIB mstr_standard
J 0
(1950 3350);
PAINT ORANGE (1950 3350);
DISPLAY INVISIBLE (1950 3350);
FORCEPROP 1 LAST PATH I127
J 2
(1952 3350);
DISPLAY 0.872340 (1952 3350);
PAINT GREEN (1952 3350);
DISPLAY INVISIBLE (1952 3350);
FORCEPROP 1 LAST BODY_TYPE PLUMBING
J 2
(1950 3300);
DISPLAY 1.234043 (1950 3300);
PAINT GREEN (1950 3300);
DISPLAY INVISIBLE (1950 3300);
FORCEPROP 1 LAST HDL_TAP TRUE
J 2
(1625 3225);
DISPLAY 1.234043 (1625 3225);
PAINT GREEN (1625 3225);
DISPLAY INVISIBLE (1625 3225);
FORCEADD TAP..6
R 2
(1700 3400);
FORCEPROP 3 LASTPIN (1650 3400) SIG_NAME P3E_CPU1_PE3_MP_TXP<5>
J 0
(1660 3410);
DISPLAY 0.659574 (1660 3410);
PAINT MONO (1660 3410);
DISPLAY INVISIBLE (1660 3410);
FORCEPROP 1 LASTPIN (1650 3400) BN 5
J 2
(1702 3408);
DISPLAY 0.617021 (1702 3408);
PAINT GREEN (1702 3408);
FORCEPROP 1 LAST PATH I128
J 2
(1702 3400);
DISPLAY 0.872340 (1702 3400);
PAINT GREEN (1702 3400);
DISPLAY INVISIBLE (1702 3400);
FORCEPROP 1 LAST BODY_TYPE PLUMBING
J 2
(1700 3350);
DISPLAY 1.234043 (1700 3350);
PAINT GREEN (1700 3350);
DISPLAY INVISIBLE (1700 3350);
FORCEPROP 2 LAST CDS_LIB mstr_standard
J 0
(1700 3400);
PAINT ORANGE (1700 3400);
DISPLAY INVISIBLE (1700 3400);
FORCEPROP 1 LAST HDL_TAP TRUE
J 2
(1375 3275);
DISPLAY 1.234043 (1375 3275);
PAINT GREEN (1375 3275);
DISPLAY INVISIBLE (1375 3275);
FORCEADD TAP..6
R 2
(1950 4050);
FORCEPROP 3 LASTPIN (1900 4050) SIG_NAME P3E_CPU1_PE3_MP_TXN<6>
J 0
(1910 4060);
DISPLAY 0.659574 (1910 4060);
PAINT MONO (1910 4060);
DISPLAY INVISIBLE (1910 4060);
FORCEPROP 1 LASTPIN (1900 4050) BN 6
J 2
(1952 4058);
DISPLAY 0.617021 (1952 4058);
PAINT GREEN (1952 4058);
FORCEPROP 2 LAST CDS_LIB mstr_standard
J 0
(1950 4050);
PAINT ORANGE (1950 4050);
DISPLAY INVISIBLE (1950 4050);
FORCEPROP 1 LAST BODY_TYPE PLUMBING
J 2
(1950 4000);
DISPLAY 1.234043 (1950 4000);
PAINT GREEN (1950 4000);
DISPLAY INVISIBLE (1950 4000);
FORCEPROP 1 LAST PATH I129
J 2
(1952 4050);
DISPLAY 0.872340 (1952 4050);
PAINT GREEN (1952 4050);
DISPLAY INVISIBLE (1952 4050);
FORCEPROP 1 LAST HDL_TAP TRUE
J 2
(1625 3925);
DISPLAY 1.234043 (1625 3925);
PAINT GREEN (1625 3925);
DISPLAY INVISIBLE (1625 3925);
FORCEADD TAP..6
R 2
(1700 4000);
FORCEPROP 3 LASTPIN (1650 4000) SIG_NAME P3E_CPU1_PE3_MP_TXP<6>
J 0
(1660 4010);
DISPLAY 0.659574 (1660 4010);
PAINT MONO (1660 4010);
DISPLAY INVISIBLE (1660 4010);
FORCEPROP 1 LASTPIN (1650 4000) BN 6
J 2
(1702 4008);
DISPLAY 0.617021 (1702 4008);
PAINT GREEN (1702 4008);
FORCEPROP 2 LAST CDS_LIB mstr_standard
J 0
(1700 4000);
PAINT ORANGE (1700 4000);
DISPLAY INVISIBLE (1700 4000);
FORCEPROP 1 LAST PATH I130
J 2
(1702 4000);
DISPLAY 0.872340 (1702 4000);
PAINT GREEN (1702 4000);
DISPLAY INVISIBLE (1702 4000);
FORCEPROP 1 LAST BODY_TYPE PLUMBING
J 2
(1700 3950);
DISPLAY 1.234043 (1700 3950);
PAINT GREEN (1700 3950);
DISPLAY INVISIBLE (1700 3950);
FORCEPROP 1 LAST HDL_TAP TRUE
J 2
(1375 3875);
DISPLAY 1.234043 (1375 3875);
PAINT GREEN (1375 3875);
DISPLAY INVISIBLE (1375 3875);
FORCEADD TAP..6
R 2
(1950 3850);
FORCEPROP 3 LASTPIN (1900 3850) SIG_NAME P3E_CPU1_PE3_MP_TXN<7>
J 0
(1910 3860);
DISPLAY 0.659574 (1910 3860);
PAINT MONO (1910 3860);
DISPLAY INVISIBLE (1910 3860);
FORCEPROP 1 LASTPIN (1900 3850) BN 7
J 2
(1952 3858);
DISPLAY 0.617021 (1952 3858);
PAINT GREEN (1952 3858);
FORCEPROP 1 LAST PATH I131
J 2
(1952 3850);
DISPLAY 0.872340 (1952 3850);
PAINT GREEN (1952 3850);
DISPLAY INVISIBLE (1952 3850);
FORCEPROP 2 LAST CDS_LIB mstr_standard
J 0
(1950 3850);
PAINT ORANGE (1950 3850);
DISPLAY INVISIBLE (1950 3850);
FORCEPROP 1 LAST BODY_TYPE PLUMBING
J 2
(1950 3800);
DISPLAY 1.234043 (1950 3800);
PAINT GREEN (1950 3800);
DISPLAY INVISIBLE (1950 3800);
FORCEPROP 1 LAST HDL_TAP TRUE
J 2
(1625 3725);
DISPLAY 1.234043 (1625 3725);
PAINT GREEN (1625 3725);
DISPLAY INVISIBLE (1625 3725);
FORCEADD TAP..6
R 2
(1700 3900);
FORCEPROP 3 LASTPIN (1650 3900) SIG_NAME P3E_CPU1_PE3_MP_TXP<7>
J 0
(1660 3910);
DISPLAY 0.659574 (1660 3910);
PAINT MONO (1660 3910);
DISPLAY INVISIBLE (1660 3910);
FORCEPROP 1 LASTPIN (1650 3900) BN 7
J 2
(1702 3908);
DISPLAY 0.617021 (1702 3908);
PAINT GREEN (1702 3908);
FORCEPROP 1 LAST PATH I132
J 2
(1702 3900);
DISPLAY 0.872340 (1702 3900);
PAINT GREEN (1702 3900);
DISPLAY INVISIBLE (1702 3900);
FORCEPROP 1 LAST BODY_TYPE PLUMBING
J 2
(1700 3850);
DISPLAY 1.234043 (1700 3850);
PAINT GREEN (1700 3850);
DISPLAY INVISIBLE (1700 3850);
FORCEPROP 2 LAST CDS_LIB mstr_standard
J 0
(1700 3900);
PAINT ORANGE (1700 3900);
DISPLAY INVISIBLE (1700 3900);
FORCEPROP 1 LAST HDL_TAP TRUE
J 2
(1375 3775);
DISPLAY 1.234043 (1375 3775);
PAINT GREEN (1375 3775);
DISPLAY INVISIBLE (1375 3775);
FORCEADD OFFPAGE..1
(-2600 2850);
FORCEPROP 2 LAST $XR0 114 
J 0
(-2852 2850);
DISPLAY 0.638298 (-2852 2850);
PAINT MONO (-2852 2850);
FORCEPROP 1 LAST OFFPAGE TRUE
J 0
(-2275 2725);
DISPLAY 0.872340 (-2275 2725);
PAINT GREEN (-2275 2725);
DISPLAY INVISIBLE (-2275 2725);
FORCEPROP 2 LAST PATH I133
J 0
(-2550 2925);
DISPLAY 1.021277 (-2550 2925);
PAINT ORANGE (-2550 2925);
DISPLAY INVISIBLE (-2550 2925);
FORCEPROP 1 LAST COMMENT_BODY TRUE
J 0
(-2475 2750);
DISPLAY 0.872340 (-2475 2750);
PAINT GREEN (-2475 2750);
DISPLAY INVISIBLE (-2475 2750);
FORCEPROP 2 LAST CDS_LIB mstr_standard
J 0
(-2600 2850);
PAINT ORANGE (-2600 2850);
DISPLAY INVISIBLE (-2600 2850);
FORCEADD OFFPAGE..1
(-2600 2800);
FORCEPROP 2 LAST $XR0 114 
J 0
(-2852 2800);
DISPLAY 0.638298 (-2852 2800);
PAINT MONO (-2852 2800);
FORCEPROP 1 LAST OFFPAGE TRUE
J 0
(-2275 2675);
DISPLAY 0.872340 (-2275 2675);
PAINT GREEN (-2275 2675);
DISPLAY INVISIBLE (-2275 2675);
FORCEPROP 2 LAST PATH I134
J 0
(-2550 2875);
DISPLAY 1.021277 (-2550 2875);
PAINT ORANGE (-2550 2875);
DISPLAY INVISIBLE (-2550 2875);
FORCEPROP 1 LAST COMMENT_BODY TRUE
J 0
(-2475 2700);
DISPLAY 0.872340 (-2475 2700);
PAINT GREEN (-2475 2700);
DISPLAY INVISIBLE (-2475 2700);
FORCEPROP 2 LAST CDS_LIB mstr_standard
J 0
(-2600 2800);
PAINT ORANGE (-2600 2800);
DISPLAY INVISIBLE (-2600 2800);
FORCEADD OFFPAGE..1
R 2
(1150 4750);
FORCEPROP 2 LAST $XR0 141 
J 0
(1336 4750);
DISPLAY 0.638298 (1336 4750);
PAINT MONO (1336 4750);
FORCEPROP 2 LAST PATH I138
J 0
(1325 4825);
DISPLAY 1.021277 (1325 4825);
PAINT ORANGE (1325 4825);
DISPLAY INVISIBLE (1325 4825);
FORCEPROP 1 LAST COMMENT_BODY TRUE
J 2
(1025 4650);
DISPLAY 0.872340 (1025 4650);
PAINT GREEN (1025 4650);
DISPLAY INVISIBLE (1025 4650);
FORCEPROP 2 LAST CDS_LIB mstr_standard
J 0
(1150 4750);
PAINT ORANGE (1150 4750);
DISPLAY INVISIBLE (1150 4750);
FORCEPROP 1 LAST OFFPAGE TRUE
J 2
(825 4625);
DISPLAY 0.872340 (825 4625);
PAINT GREEN (825 4625);
DISPLAY INVISIBLE (825 4625);
FORCEADD OFFPAGE..1
R 2
(1150 4700);
FORCEPROP 2 LAST $XR0 141 
J 0
(1336 4700);
DISPLAY 0.638298 (1336 4700);
PAINT MONO (1336 4700);
FORCEPROP 2 LAST PATH I139
J 0
(1325 4775);
DISPLAY 1.021277 (1325 4775);
PAINT ORANGE (1325 4775);
DISPLAY INVISIBLE (1325 4775);
FORCEPROP 2 LAST CDS_LIB mstr_standard
J 0
(1150 4700);
PAINT ORANGE (1150 4700);
DISPLAY INVISIBLE (1150 4700);
FORCEPROP 1 LAST COMMENT_BODY TRUE
J 2
(1025 4600);
DISPLAY 0.872340 (1025 4600);
PAINT GREEN (1025 4600);
DISPLAY INVISIBLE (1025 4600);
FORCEPROP 1 LAST OFFPAGE TRUE
J 2
(825 4575);
DISPLAY 0.872340 (825 4575);
PAINT GREEN (825 4575);
DISPLAY INVISIBLE (825 4575);
FORCEADD OFFPAGE..2
(1150 4600);
FORCEPROP 2 LAST $XR0 141 
J 0
(1339 4600);
DISPLAY 0.638298 (1339 4600);
PAINT MONO (1339 4600);
FORCEPROP 2 LAST CDS_LIB mstr_standard
J 2
(1150 4600);
PAINT ORANGE (1150 4600);
DISPLAY INVISIBLE (1150 4600);
FORCEPROP 1 LAST OFFPAGE TRUE
J 0
(1475 4475);
DISPLAY 0.872340 (1475 4475);
PAINT GREEN (1475 4475);
DISPLAY INVISIBLE (1475 4475);
FORCEPROP 1 LAST COMMENT_BODY TRUE
J 0
(1105 4505);
DISPLAY 0.872340 (1105 4505);
PAINT GREEN (1105 4505);
DISPLAY INVISIBLE (1105 4505);
FORCEPROP 2 LAST PATH I140
J 2
(975 4675);
DISPLAY 1.021277 (975 4675);
PAINT ORANGE (975 4675);
DISPLAY INVISIBLE (975 4675);
FORCEADD OFFPAGE..2
(1150 4550);
FORCEPROP 2 LAST $XR0 141 
J 0
(1339 4550);
DISPLAY 0.638298 (1339 4550);
PAINT MONO (1339 4550);
FORCEPROP 2 LAST PATH I141
J 0
(1325 4625);
DISPLAY 1.021277 (1325 4625);
PAINT ORANGE (1325 4625);
DISPLAY INVISIBLE (1325 4625);
FORCEPROP 1 LAST OFFPAGE TRUE
J 0
(1475 4425);
DISPLAY 0.872340 (1475 4425);
PAINT GREEN (1475 4425);
DISPLAY INVISIBLE (1475 4425);
FORCEPROP 2 LAST CDS_LIB mstr_standard
J 0
(1150 4550);
PAINT ORANGE (1150 4550);
DISPLAY INVISIBLE (1150 4550);
FORCEPROP 1 LAST COMMENT_BODY TRUE
J 0
(1105 4455);
DISPLAY 0.872340 (1105 4455);
PAINT GREEN (1105 4455);
DISPLAY INVISIBLE (1105 4455);
FORCEADD OFFPAGE..1
R 2
(1150 4350);
FORCEPROP 2 LAST $XR0 191 
J 0
(1336 4350);
DISPLAY 0.638298 (1336 4350);
PAINT MONO (1336 4350);
FORCEPROP 2 LAST CDS_LIB mstr_standard
J 2
(1150 4350);
PAINT ORANGE (1150 4350);
DISPLAY INVISIBLE (1150 4350);
FORCEPROP 1 LAST COMMENT_BODY TRUE
J 2
(1025 4250);
DISPLAY 0.872340 (1025 4250);
PAINT GREEN (1025 4250);
DISPLAY INVISIBLE (1025 4250);
FORCEPROP 2 LAST PATH I142
J 2
(975 4425);
DISPLAY 1.021277 (975 4425);
PAINT ORANGE (975 4425);
DISPLAY INVISIBLE (975 4425);
FORCEPROP 1 LAST OFFPAGE TRUE
J 2
(825 4225);
DISPLAY 0.872340 (825 4225);
PAINT GREEN (825 4225);
DISPLAY INVISIBLE (825 4225);
FORCEADD OFFPAGE..5
(-3475 5075);
FORCEPROP 2 LAST $XR0 66 
J 0
(-3729 5075);
DISPLAY 0.638298 (-3729 5075);
PAINT MONO (-3729 5075);
FORCEPROP 2 LAST PATH I143
J 0
(-3425 5150);
DISPLAY 1.021277 (-3425 5150);
PAINT ORANGE (-3425 5150);
DISPLAY INVISIBLE (-3425 5150);
FORCEPROP 1 LAST OFFPAGE TRUE
J 0
(-3150 4950);
DISPLAY 0.872340 (-3150 4950);
PAINT GREEN (-3150 4950);
DISPLAY INVISIBLE (-3150 4950);
FORCEPROP 1 LAST COMMENT_BODY TRUE
J 0
(-3375 5000);
DISPLAY 0.872340 (-3375 5000);
PAINT GREEN (-3375 5000);
DISPLAY INVISIBLE (-3375 5000);
FORCEPROP 2 LAST CDS_LIB mstr_standard
J 0
(-3475 5075);
PAINT ORANGE (-3475 5075);
DISPLAY INVISIBLE (-3475 5075);
FORCEADD OFFPAGE..5
(-3475 4950);
FORCEPROP 2 LAST $XR0 66 
J 0
(-3729 4950);
DISPLAY 0.638298 (-3729 4950);
PAINT MONO (-3729 4950);
FORCEPROP 1 LAST OFFPAGE TRUE
J 0
(-3150 4825);
DISPLAY 0.872340 (-3150 4825);
PAINT GREEN (-3150 4825);
DISPLAY INVISIBLE (-3150 4825);
FORCEPROP 2 LAST PATH I144
J 0
(-3425 5025);
DISPLAY 1.021277 (-3425 5025);
PAINT ORANGE (-3425 5025);
DISPLAY INVISIBLE (-3425 5025);
FORCEPROP 1 LAST COMMENT_BODY TRUE
J 0
(-3375 4875);
DISPLAY 0.872340 (-3375 4875);
PAINT GREEN (-3375 4875);
DISPLAY INVISIBLE (-3375 4875);
FORCEPROP 2 LAST CDS_LIB mstr_standard
J 0
(-3475 4950);
PAINT ORANGE (-3475 4950);
DISPLAY INVISIBLE (-3475 4950);
FORCEADD OFFPAGE..1
R 2
(3075 4825);
FORCEPROP 2 LAST $XR0 66 
J 0
(3261 4825);
DISPLAY 0.638298 (3261 4825);
PAINT MONO (3261 4825);
FORCEPROP 2 LAST PATH I145
J 0
(3250 4900);
DISPLAY 1.021277 (3250 4900);
PAINT ORANGE (3250 4900);
DISPLAY INVISIBLE (3250 4900);
FORCEPROP 2 LAST CDS_LIB mstr_standard
J 0
(3075 4825);
PAINT ORANGE (3075 4825);
DISPLAY INVISIBLE (3075 4825);
FORCEPROP 1 LAST COMMENT_BODY TRUE
J 2
(2950 4725);
DISPLAY 0.872340 (2950 4725);
PAINT GREEN (2950 4725);
DISPLAY INVISIBLE (2950 4725);
FORCEPROP 1 LAST OFFPAGE TRUE
J 2
(2750 4700);
DISPLAY 0.872340 (2750 4700);
PAINT GREEN (2750 4700);
DISPLAY INVISIBLE (2750 4700);
FORCEADD OFFPAGE..1
R 2
(3075 4725);
FORCEPROP 2 LAST $XR0 66 
J 0
(3261 4725);
DISPLAY 0.638298 (3261 4725);
PAINT MONO (3261 4725);
FORCEPROP 2 LAST PATH I146
J 0
(3250 4800);
DISPLAY 1.021277 (3250 4800);
PAINT ORANGE (3250 4800);
DISPLAY INVISIBLE (3250 4800);
FORCEPROP 2 LAST CDS_LIB mstr_standard
J 0
(3075 4725);
PAINT ORANGE (3075 4725);
DISPLAY INVISIBLE (3075 4725);
FORCEPROP 1 LAST COMMENT_BODY TRUE
J 2
(2950 4625);
DISPLAY 0.872340 (2950 4625);
PAINT GREEN (2950 4625);
DISPLAY INVISIBLE (2950 4625);
FORCEPROP 1 LAST OFFPAGE TRUE
J 2
(2750 4600);
DISPLAY 0.872340 (2750 4600);
PAINT GREEN (2750 4600);
DISPLAY INVISIBLE (2750 4600);
FORCEADD OFFPAGE..6
(-2600 3000);
FORCEPROP 2 LAST $XR0 181 
J 0
(-2880 3000);
DISPLAY 0.638298 (-2880 3000);
PAINT MONO (-2880 3000);
FORCEPROP 2 LAST PATH I152
J 0
(-2550 3075);
DISPLAY 1.021277 (-2550 3075);
PAINT ORANGE (-2550 3075);
DISPLAY INVISIBLE (-2550 3075);
FORCEPROP 1 LAST OFFPAGE TRUE
J 0
(-2275 2875);
DISPLAY 0.872340 (-2275 2875);
PAINT GREEN (-2275 2875);
DISPLAY INVISIBLE (-2275 2875);
FORCEPROP 1 LAST COMMENT_BODY TRUE
J 0
(-2500 2925);
DISPLAY 0.872340 (-2500 2925);
PAINT GREEN (-2500 2925);
DISPLAY INVISIBLE (-2500 2925);
FORCEPROP 2 LAST CDS_LIB mstr_standard
J 0
(-2600 3000);
PAINT ORANGE (-2600 3000);
DISPLAY INVISIBLE (-2600 3000);
FORCEADD OFFPAGE..2
(1150 4250);
FORCEPROP 2 LAST $XR1 199 
J 0
(1459 4250);
DISPLAY 0.638298 (1459 4250);
PAINT MONO (1459 4250);
FORCEPROP 2 LAST $XR0 181 
J 0
(1339 4250);
DISPLAY 0.638298 (1339 4250);
PAINT MONO (1339 4250);
FORCEPROP 2 LAST PATH I157
J 0
(1325 4325);
DISPLAY 1.021277 (1325 4325);
PAINT ORANGE (1325 4325);
DISPLAY INVISIBLE (1325 4325);
FORCEPROP 1 LAST OFFPAGE TRUE
J 0
(1475 4125);
DISPLAY 0.872340 (1475 4125);
PAINT GREEN (1475 4125);
DISPLAY INVISIBLE (1475 4125);
FORCEPROP 2 LAST CDS_LIB mstr_standard
J 0
(1150 4250);
PAINT ORANGE (1150 4250);
DISPLAY INVISIBLE (1150 4250);
FORCEPROP 1 LAST COMMENT_BODY TRUE
J 0
(1105 4155);
DISPLAY 0.872340 (1105 4155);
PAINT GREEN (1105 4155);
DISPLAY INVISIBLE (1105 4155);
FORCEADD OFFPAGE..3
(1150 4150);
FORCEPROP 2 LAST $XR4 199 
J 0
(1364 4114);
DISPLAY 0.638298 (1364 4114);
PAINT MONO (1364 4114);
FORCEPROP 2 LAST $XR3 181 
J 0
(1364 4114);
DISPLAY 0.638298 (1364 4114);
PAINT MONO (1364 4114);
FORCEPROP 2 LAST $XR2 247 
J 0
(1604 4150);
DISPLAY 0.638298 (1604 4150);
PAINT MONO (1604 4150);
FORCEPROP 2 LAST $XR1 159 
J 0
(1484 4150);
DISPLAY 0.638298 (1484 4150);
PAINT MONO (1484 4150);
FORCEPROP 2 LAST $XR0 138 
J 0
(1364 4150);
DISPLAY 0.638298 (1364 4150);
PAINT MONO (1364 4150);
FORCEPROP 2 LAST PATH I158
J 0
(1325 4225);
DISPLAY 1.021277 (1325 4225);
PAINT ORANGE (1325 4225);
DISPLAY INVISIBLE (1325 4225);
FORCEPROP 2 LAST CDS_LIB mstr_standard
J 0
(1150 4150);
PAINT ORANGE (1150 4150);
DISPLAY INVISIBLE (1150 4150);
FORCEPROP 1 LAST OFFPAGE TRUE
J 0
(1475 4025);
DISPLAY 0.872340 (1475 4025);
PAINT GREEN (1475 4025);
DISPLAY INVISIBLE (1475 4025);
FORCEPROP 1 LAST COMMENT_BODY TRUE
J 0
(1100 4050);
DISPLAY 0.872340 (1100 4050);
PAINT GREEN (1100 4050);
DISPLAY INVISIBLE (1100 4050);
FORCEADD OFFPAGE..3
(1150 4200);
FORCEPROP 2 LAST $XR4 247 
J 0
(1604 4236);
DISPLAY 0.638298 (1604 4236);
PAINT MONO (1604 4236);
FORCEPROP 2 LAST $XR3 199 
J 0
(1604 4236);
DISPLAY 0.638298 (1604 4236);
PAINT MONO (1604 4236);
FORCEPROP 2 LAST $XR2 181 
J 0
(1604 4200);
DISPLAY 0.638298 (1604 4200);
PAINT MONO (1604 4200);
FORCEPROP 2 LAST $XR1 159 
J 0
(1484 4200);
DISPLAY 0.638298 (1484 4200);
PAINT MONO (1484 4200);
FORCEPROP 2 LAST $XR0 138 
J 0
(1364 4200);
DISPLAY 0.638298 (1364 4200);
PAINT MONO (1364 4200);
FORCEPROP 2 LAST PATH I159
J 0
(1350 4275);
DISPLAY 1.021277 (1350 4275);
PAINT ORANGE (1350 4275);
DISPLAY INVISIBLE (1350 4275);
FORCEPROP 2 LAST CDS_LIB mstr_standard
J 0
(1150 4200);
PAINT ORANGE (1150 4200);
DISPLAY INVISIBLE (1150 4200);
FORCEPROP 1 LAST COMMENT_BODY TRUE
J 0
(1100 4100);
DISPLAY 0.872340 (1100 4100);
PAINT GREEN (1100 4100);
DISPLAY INVISIBLE (1100 4100);
FORCEPROP 1 LAST OFFPAGE TRUE
J 0
(1475 4075);
DISPLAY 0.872340 (1475 4075);
PAINT GREEN (1475 4075);
DISPLAY INVISIBLE (1475 4075);
FORCEADD CAP..2
(1025 4050);
FORCEPROP 1 LAST PACK_TYPE 0402
J 1
(1550 4025);
DISPLAY 0.617021 (1550 4025);
PAINT SKYBLUE (1550 4025);
FORCEPROP 1 LAST LOCATION C1F4
J 1
(1025 4100);
DISPLAY 0.617021 (1025 4100);
PAINT AQUA (1025 4100);
FORCEPROP 1 LAST PART_NUMBER A36096-155
J 1
(1300 4075);
DISPLAY 0.617021 (1300 4075);
PAINT BLUE (1300 4075);
FORCEPROP 1 LAST TOLERANCE 10%
J 2
(1450 4025);
DISPLAY 0.617021 (1450 4025);
PAINT SKYBLUE (1450 4025);
FORCEPROP 1 LAST MATERIAL X7R
J 0
(1250 4025);
DISPLAY 0.617021 (1250 4025);
PAINT SKYBLUE (1250 4025);
FORCEPROP 1 LAST VOLTAGE 16V
J 0
(1125 4025);
DISPLAY 0.617021 (1125 4025);
PAINT SKYBLUE (1125 4025);
FORCEPROP 1 LASTPIN (1125 4050) $PN 2
J 0
(1110 4065);
DISPLAY 0.617021 (1110 4065);
PAINT ORANGE (1110 4065);
FORCEPROP 1 LASTPIN (925 4050) $PN 1
J 0
(915 4065);
DISPLAY 0.617021 (915 4065);
PAINT ORANGE (915 4065);
FORCEPROP 1 LAST VALUE 0.22UF
J 2
(975 4025);
DISPLAY 0.617021 (975 4025);
PAINT SKYBLUE (975 4025);
FORCEPROP 1 LAST PATH I160
J 0
(1025 4250);
DISPLAY 0.978723 (1025 4250);
PAINT WHITE (1025 4250);
DISPLAY INVISIBLE (1025 4250);
FORCEPROP 2 LAST SEC 1
J 0
(1025 4300);
DISPLAY 0.680851 (1025 4300);
PAINT MONO (1025 4300);
DISPLAY INVISIBLE (1025 4300);
FORCEPROP 2 LAST SEC_TYPE 0402
J 0
(1025 4300);
DISPLAY 1.021277 (1025 4300);
PAINT ORANGE (1025 4300);
DISPLAY INVISIBLE (1025 4300);
FORCEPROP 0 LAST ROOM IO_SLOT
J 0
(1025 4250);
DISPLAY 1.021277 (1025 4250);
PAINT ORANGE (1025 4250);
DISPLAY INVISIBLE (1025 4250);
FORCEPROP 0 LAST BOM_COST IO_SLOT
J 0
(1025 4200);
DISPLAY 1.021277 (1025 4200);
PAINT ORANGE (1025 4200);
DISPLAY INVISIBLE (1025 4200);
FORCEPROP 2 LAST CDS_LOCATION C1F4
J 1
(1025 4100);
DISPLAY 0.617021 (1025 4100);
PAINT AQUA (1025 4100);
DISPLAY INVISIBLE (1025 4100);
FORCEPROP 2 LAST CDS_LIB mstr_discrete
J 0
(1025 4050);
PAINT ORANGE (1025 4050);
DISPLAY INVISIBLE (1025 4050);
FORCEADD CAP..2
(600 4000);
FORCEPROP 1 LAST LOCATION C1F5
J 1
(600 4100);
DISPLAY 0.617021 (600 4100);
PAINT AQUA (600 4100);
FORCEPROP 1 LAST PACK_TYPE 0402
J 1
(1125 3975);
DISPLAY 0.617021 (1125 3975);
PAINT SKYBLUE (1125 3975);
FORCEPROP 1 LAST TOLERANCE 10%
J 2
(1025 3975);
DISPLAY 0.617021 (1025 3975);
PAINT SKYBLUE (1025 3975);
FORCEPROP 1 LAST MATERIAL X7R
J 0
(825 3975);
DISPLAY 0.617021 (825 3975);
PAINT SKYBLUE (825 3975);
FORCEPROP 1 LAST VOLTAGE 16V
J 0
(700 3975);
DISPLAY 0.617021 (700 3975);
PAINT SKYBLUE (700 3975);
FORCEPROP 1 LASTPIN (700 4000) $PN 2
J 0
(685 4015);
DISPLAY 0.617021 (685 4015);
PAINT ORANGE (685 4015);
FORCEPROP 1 LASTPIN (500 4000) $PN 1
J 0
(490 4015);
DISPLAY 0.617021 (490 4015);
PAINT ORANGE (490 4015);
FORCEPROP 1 LAST VALUE 0.22UF
J 2
(525 3950);
DISPLAY 0.617021 (525 3950);
PAINT SKYBLUE (525 3950);
FORCEPROP 1 LAST PART_NUMBER A36096-155
J 1
(600 4050);
DISPLAY 0.617021 (600 4050);
PAINT BLUE (600 4050);
FORCEPROP 1 LAST PATH I161
J 0
(600 4200);
DISPLAY 0.978723 (600 4200);
PAINT WHITE (600 4200);
DISPLAY INVISIBLE (600 4200);
FORCEPROP 2 LAST CDS_LOCATION C1F5
J 1
(600 4100);
DISPLAY 0.617021 (600 4100);
PAINT AQUA (600 4100);
DISPLAY INVISIBLE (600 4100);
FORCEPROP 2 LAST SEC 1
J 0
(600 4250);
DISPLAY 0.680851 (600 4250);
PAINT MONO (600 4250);
DISPLAY INVISIBLE (600 4250);
FORCEPROP 2 LAST SEC_TYPE 0402
J 0
(600 4250);
DISPLAY 1.021277 (600 4250);
PAINT ORANGE (600 4250);
DISPLAY INVISIBLE (600 4250);
FORCEPROP 0 LAST BOM_COST IO_SLOT
J 0
(600 4150);
DISPLAY 1.021277 (600 4150);
PAINT ORANGE (600 4150);
DISPLAY INVISIBLE (600 4150);
FORCEPROP 0 LAST ROOM IO_SLOT
J 0
(600 4200);
DISPLAY 1.021277 (600 4200);
PAINT ORANGE (600 4200);
DISPLAY INVISIBLE (600 4200);
FORCEPROP 2 LAST CDS_LIB mstr_discrete
J 0
(600 4000);
PAINT ORANGE (600 4000);
DISPLAY INVISIBLE (600 4000);
FORCEADD CAP..2
(1025 3900);
FORCEPROP 1 LAST MATERIAL X7R
J 0
(1250 3875);
DISPLAY 0.617021 (1250 3875);
PAINT SKYBLUE (1250 3875);
FORCEPROP 1 LAST PART_NUMBER A36096-155
J 1
(1300 3925);
DISPLAY 0.617021 (1300 3925);
PAINT BLUE (1300 3925);
FORCEPROP 1 LAST PACK_TYPE 0402
J 1
(1550 3875);
DISPLAY 0.617021 (1550 3875);
PAINT SKYBLUE (1550 3875);
FORCEPROP 1 LAST TOLERANCE 10%
J 2
(1450 3875);
DISPLAY 0.617021 (1450 3875);
PAINT SKYBLUE (1450 3875);
FORCEPROP 1 LAST VOLTAGE 16V
J 0
(1125 3875);
DISPLAY 0.617021 (1125 3875);
PAINT SKYBLUE (1125 3875);
FORCEPROP 1 LASTPIN (1125 3900) $PN 2
J 0
(1110 3915);
DISPLAY 0.617021 (1110 3915);
PAINT ORANGE (1110 3915);
FORCEPROP 1 LAST LOCATION C1F2
J 1
(1025 4000);
DISPLAY 0.617021 (1025 4000);
PAINT AQUA (1025 4000);
FORCEPROP 1 LAST VALUE 0.22UF
J 2
(975 3875);
DISPLAY 0.617021 (975 3875);
PAINT SKYBLUE (975 3875);
FORCEPROP 1 LASTPIN (925 3900) $PN 1
J 0
(915 3915);
DISPLAY 0.617021 (915 3915);
PAINT ORANGE (915 3915);
FORCEPROP 1 LAST PATH I162
J 0
(1025 4100);
DISPLAY 0.978723 (1025 4100);
PAINT WHITE (1025 4100);
DISPLAY INVISIBLE (1025 4100);
FORCEPROP 2 LAST SEC 1
J 0
(1025 4150);
DISPLAY 0.680851 (1025 4150);
PAINT MONO (1025 4150);
DISPLAY INVISIBLE (1025 4150);
FORCEPROP 2 LAST SEC_TYPE 0402
J 0
(1025 4150);
DISPLAY 1.021277 (1025 4150);
PAINT ORANGE (1025 4150);
DISPLAY INVISIBLE (1025 4150);
FORCEPROP 0 LAST ROOM IO_SLOT
J 0
(1025 4100);
DISPLAY 1.021277 (1025 4100);
PAINT ORANGE (1025 4100);
DISPLAY INVISIBLE (1025 4100);
FORCEPROP 0 LAST BOM_COST IO_SLOT
J 0
(1025 4050);
DISPLAY 1.021277 (1025 4050);
PAINT ORANGE (1025 4050);
DISPLAY INVISIBLE (1025 4050);
FORCEPROP 2 LAST CDS_LOCATION C1F2
J 1
(1025 4000);
DISPLAY 0.617021 (1025 4000);
PAINT AQUA (1025 4000);
DISPLAY INVISIBLE (1025 4000);
FORCEPROP 2 LAST CDS_LIB mstr_discrete
J 0
(1025 3900);
PAINT ORANGE (1025 3900);
DISPLAY INVISIBLE (1025 3900);
FORCEADD CAP..2
(1025 3700);
FORCEPROP 1 LAST PART_NUMBER A36096-155
J 1
(1300 3725);
DISPLAY 0.617021 (1300 3725);
PAINT BLUE (1300 3725);
FORCEPROP 1 LAST PACK_TYPE 0402
J 1
(1550 3675);
DISPLAY 0.617021 (1550 3675);
PAINT SKYBLUE (1550 3675);
FORCEPROP 1 LAST TOLERANCE 10%
J 2
(1450 3675);
DISPLAY 0.617021 (1450 3675);
PAINT SKYBLUE (1450 3675);
FORCEPROP 1 LAST MATERIAL X7R
J 0
(1250 3675);
DISPLAY 0.617021 (1250 3675);
PAINT SKYBLUE (1250 3675);
FORCEPROP 1 LAST VOLTAGE 16V
J 0
(1125 3675);
DISPLAY 0.617021 (1125 3675);
PAINT SKYBLUE (1125 3675);
FORCEPROP 1 LASTPIN (1125 3700) $PN 2
J 0
(1110 3715);
DISPLAY 0.617021 (1110 3715);
PAINT ORANGE (1110 3715);
FORCEPROP 1 LAST LOCATION C1F13
J 1
(1025 3800);
DISPLAY 0.617021 (1025 3800);
PAINT AQUA (1025 3800);
FORCEPROP 1 LAST VALUE 0.22UF
J 2
(975 3675);
DISPLAY 0.617021 (975 3675);
PAINT SKYBLUE (975 3675);
FORCEPROP 1 LASTPIN (925 3700) $PN 1
J 0
(915 3715);
DISPLAY 0.617021 (915 3715);
PAINT ORANGE (915 3715);
FORCEPROP 2 LAST SEC 1
J 0
(1025 3950);
DISPLAY 0.680851 (1025 3950);
PAINT MONO (1025 3950);
DISPLAY INVISIBLE (1025 3950);
FORCEPROP 2 LAST SEC_TYPE 0402
J 0
(1025 3950);
DISPLAY 1.021277 (1025 3950);
PAINT ORANGE (1025 3950);
DISPLAY INVISIBLE (1025 3950);
FORCEPROP 1 LAST PATH I163
J 0
(1025 3900);
DISPLAY 0.978723 (1025 3900);
PAINT WHITE (1025 3900);
DISPLAY INVISIBLE (1025 3900);
FORCEPROP 0 LAST BOM_COST IO_SLOT
J 0
(1025 3850);
DISPLAY 1.021277 (1025 3850);
PAINT ORANGE (1025 3850);
DISPLAY INVISIBLE (1025 3850);
FORCEPROP 0 LAST ROOM IO_SLOT
J 0
(1025 3900);
DISPLAY 1.021277 (1025 3900);
PAINT ORANGE (1025 3900);
DISPLAY INVISIBLE (1025 3900);
FORCEPROP 2 LAST CDS_LOCATION C1F13
J 1
(1025 3800);
DISPLAY 0.617021 (1025 3800);
PAINT AQUA (1025 3800);
DISPLAY INVISIBLE (1025 3800);
FORCEPROP 2 LAST CDS_LIB mstr_discrete
J 0
(1025 3700);
PAINT ORANGE (1025 3700);
DISPLAY INVISIBLE (1025 3700);
FORCEADD CAP..2
(1050 3550);
FORCEPROP 1 LAST LOCATION C1F10
J 1
(1050 3650);
DISPLAY 0.617021 (1050 3650);
PAINT AQUA (1050 3650);
FORCEPROP 1 LAST PACK_TYPE 0402
J 1
(1575 3525);
DISPLAY 0.617021 (1575 3525);
PAINT SKYBLUE (1575 3525);
FORCEPROP 1 LASTPIN (1150 3550) $PN 2
J 0
(1135 3565);
DISPLAY 0.617021 (1135 3565);
PAINT ORANGE (1135 3565);
FORCEPROP 1 LAST PART_NUMBER A36096-155
J 1
(1325 3575);
DISPLAY 0.617021 (1325 3575);
PAINT BLUE (1325 3575);
FORCEPROP 1 LAST TOLERANCE 10%
J 2
(1475 3525);
DISPLAY 0.617021 (1475 3525);
PAINT SKYBLUE (1475 3525);
FORCEPROP 1 LAST MATERIAL X7R
J 0
(1275 3525);
DISPLAY 0.617021 (1275 3525);
PAINT SKYBLUE (1275 3525);
FORCEPROP 1 LAST VOLTAGE 16V
J 0
(1150 3525);
DISPLAY 0.617021 (1150 3525);
PAINT SKYBLUE (1150 3525);
FORCEPROP 1 LASTPIN (950 3550) $PN 1
J 0
(940 3565);
DISPLAY 0.617021 (940 3565);
PAINT ORANGE (940 3565);
FORCEPROP 1 LAST VALUE 0.22UF
J 2
(1000 3525);
DISPLAY 0.617021 (1000 3525);
PAINT SKYBLUE (1000 3525);
FORCEPROP 2 LAST SEC_TYPE 0402
J 0
(1050 3800);
DISPLAY 1.021277 (1050 3800);
PAINT ORANGE (1050 3800);
DISPLAY INVISIBLE (1050 3800);
FORCEPROP 1 LAST PATH I164
J 0
(1050 3750);
DISPLAY 0.978723 (1050 3750);
PAINT WHITE (1050 3750);
DISPLAY INVISIBLE (1050 3750);
FORCEPROP 2 LAST SEC 1
J 0
(1050 3800);
DISPLAY 0.680851 (1050 3800);
PAINT MONO (1050 3800);
DISPLAY INVISIBLE (1050 3800);
FORCEPROP 0 LAST ROOM IO_SLOT
J 0
(1050 3750);
DISPLAY 1.021277 (1050 3750);
PAINT ORANGE (1050 3750);
DISPLAY INVISIBLE (1050 3750);
FORCEPROP 0 LAST BOM_COST IO_SLOT
J 0
(1050 3700);
DISPLAY 1.021277 (1050 3700);
PAINT ORANGE (1050 3700);
DISPLAY INVISIBLE (1050 3700);
FORCEPROP 2 LAST CDS_LOCATION C1F10
J 1
(1050 3650);
DISPLAY 0.617021 (1050 3650);
PAINT AQUA (1050 3650);
DISPLAY INVISIBLE (1050 3650);
FORCEPROP 2 LAST CDS_LIB mstr_discrete
J 0
(1050 3550);
PAINT ORANGE (1050 3550);
DISPLAY INVISIBLE (1050 3550);
FORCEADD CAP..2
(1050 3400);
FORCEPROP 1 LAST PACK_TYPE 0402
J 1
(1575 3375);
DISPLAY 0.617021 (1575 3375);
PAINT SKYBLUE (1575 3375);
FORCEPROP 1 LAST TOLERANCE 10%
J 2
(1475 3375);
DISPLAY 0.617021 (1475 3375);
PAINT SKYBLUE (1475 3375);
FORCEPROP 1 LAST MATERIAL X7R
J 0
(1275 3375);
DISPLAY 0.617021 (1275 3375);
PAINT SKYBLUE (1275 3375);
FORCEPROP 1 LAST PART_NUMBER A36096-155
J 1
(1350 3425);
DISPLAY 0.617021 (1350 3425);
PAINT BLUE (1350 3425);
FORCEPROP 1 LASTPIN (1150 3400) $PN 2
J 0
(1135 3415);
DISPLAY 0.617021 (1135 3415);
PAINT ORANGE (1135 3415);
FORCEPROP 1 LAST VOLTAGE 16V
J 0
(1150 3375);
DISPLAY 0.617021 (1150 3375);
PAINT SKYBLUE (1150 3375);
FORCEPROP 1 LAST LOCATION C1F6
J 1
(1050 3500);
DISPLAY 0.617021 (1050 3500);
PAINT AQUA (1050 3500);
FORCEPROP 1 LASTPIN (950 3400) $PN 1
J 0
(940 3415);
DISPLAY 0.617021 (940 3415);
PAINT ORANGE (940 3415);
FORCEPROP 1 LAST VALUE 0.22UF
J 2
(1000 3375);
DISPLAY 0.617021 (1000 3375);
PAINT SKYBLUE (1000 3375);
FORCEPROP 1 LAST PATH I165
J 0
(1050 3600);
DISPLAY 0.978723 (1050 3600);
PAINT WHITE (1050 3600);
DISPLAY INVISIBLE (1050 3600);
FORCEPROP 2 LAST SEC 1
J 0
(1050 3650);
DISPLAY 0.680851 (1050 3650);
PAINT MONO (1050 3650);
DISPLAY INVISIBLE (1050 3650);
FORCEPROP 2 LAST SEC_TYPE 0402
J 0
(1050 3650);
DISPLAY 1.021277 (1050 3650);
PAINT ORANGE (1050 3650);
DISPLAY INVISIBLE (1050 3650);
FORCEPROP 0 LAST ROOM IO_SLOT
J 0
(1050 3600);
DISPLAY 1.021277 (1050 3600);
PAINT ORANGE (1050 3600);
DISPLAY INVISIBLE (1050 3600);
FORCEPROP 0 LAST BOM_COST IO_SLOT
J 0
(1050 3550);
DISPLAY 1.021277 (1050 3550);
PAINT ORANGE (1050 3550);
DISPLAY INVISIBLE (1050 3550);
FORCEPROP 2 LAST CDS_LOCATION C1F6
J 1
(1050 3500);
DISPLAY 0.617021 (1050 3500);
PAINT AQUA (1050 3500);
DISPLAY INVISIBLE (1050 3500);
FORCEPROP 2 LAST CDS_LIB mstr_discrete
J 0
(1050 3400);
PAINT ORANGE (1050 3400);
DISPLAY INVISIBLE (1050 3400);
FORCEADD CAP..2
(1050 3150);
FORCEPROP 1 LAST PACK_TYPE 0402
J 1
(1575 3125);
DISPLAY 0.617021 (1575 3125);
PAINT SKYBLUE (1575 3125);
FORCEPROP 1 LAST TOLERANCE 10%
J 2
(1475 3125);
DISPLAY 0.617021 (1475 3125);
PAINT SKYBLUE (1475 3125);
FORCEPROP 1 LAST MATERIAL X7R
J 0
(1275 3125);
DISPLAY 0.617021 (1275 3125);
PAINT SKYBLUE (1275 3125);
FORCEPROP 1 LAST PART_NUMBER A36096-155
J 1
(1350 3175);
DISPLAY 0.617021 (1350 3175);
PAINT BLUE (1350 3175);
FORCEPROP 1 LAST VOLTAGE 16V
J 0
(1150 3125);
DISPLAY 0.617021 (1150 3125);
PAINT SKYBLUE (1150 3125);
FORCEPROP 1 LASTPIN (1150 3150) $PN 2
J 0
(1135 3165);
DISPLAY 0.617021 (1135 3165);
PAINT ORANGE (1135 3165);
FORCEPROP 1 LAST LOCATION C1F20
J 1
(1050 3225);
DISPLAY 0.617021 (1050 3225);
PAINT AQUA (1050 3225);
FORCEPROP 1 LASTPIN (950 3150) $PN 1
J 0
(940 3165);
DISPLAY 0.617021 (940 3165);
PAINT ORANGE (940 3165);
FORCEPROP 1 LAST VALUE 0.22UF
J 2
(1000 3125);
DISPLAY 0.617021 (1000 3125);
PAINT SKYBLUE (1000 3125);
FORCEPROP 1 LAST PATH I166
J 0
(1050 3350);
DISPLAY 0.978723 (1050 3350);
PAINT WHITE (1050 3350);
DISPLAY INVISIBLE (1050 3350);
FORCEPROP 2 LAST SEC 1
J 0
(1050 3400);
DISPLAY 0.680851 (1050 3400);
PAINT MONO (1050 3400);
DISPLAY INVISIBLE (1050 3400);
FORCEPROP 2 LAST SEC_TYPE 0402
J 0
(1050 3400);
DISPLAY 1.021277 (1050 3400);
PAINT ORANGE (1050 3400);
DISPLAY INVISIBLE (1050 3400);
FORCEPROP 0 LAST ROOM IO_SLOT
J 0
(1050 3350);
DISPLAY 1.021277 (1050 3350);
PAINT ORANGE (1050 3350);
DISPLAY INVISIBLE (1050 3350);
FORCEPROP 0 LAST BOM_COST IO_SLOT
J 0
(1050 3300);
DISPLAY 1.021277 (1050 3300);
PAINT ORANGE (1050 3300);
DISPLAY INVISIBLE (1050 3300);
FORCEPROP 2 LAST CDS_LIB mstr_discrete
J 0
(1050 3150);
PAINT ORANGE (1050 3150);
DISPLAY INVISIBLE (1050 3150);
FORCEPROP 2 LAST CDS_LOCATION C1F20
J 1
(1050 3225);
DISPLAY 0.617021 (1050 3225);
PAINT AQUA (1050 3225);
DISPLAY INVISIBLE (1050 3225);
FORCEADD CAP..2
(600 3850);
FORCEPROP 1 LAST PACK_TYPE 0402
J 1
(1125 3825);
DISPLAY 0.617021 (1125 3825);
PAINT SKYBLUE (1125 3825);
FORCEPROP 1 LAST TOLERANCE 10%
J 2
(1025 3825);
DISPLAY 0.617021 (1025 3825);
PAINT SKYBLUE (1025 3825);
FORCEPROP 1 LAST MATERIAL X7R
J 0
(825 3825);
DISPLAY 0.617021 (825 3825);
PAINT SKYBLUE (825 3825);
FORCEPROP 1 LAST VOLTAGE 16V
J 0
(700 3825);
DISPLAY 0.617021 (700 3825);
PAINT SKYBLUE (700 3825);
FORCEPROP 1 LAST PART_NUMBER A36096-155
J 1
(750 3900);
DISPLAY 0.617021 (750 3900);
PAINT BLUE (750 3900);
FORCEPROP 1 LASTPIN (700 3850) $PN 2
J 0
(685 3865);
DISPLAY 0.617021 (685 3865);
PAINT ORANGE (685 3865);
FORCEPROP 1 LAST LOCATION C1F3
J 1
(600 3925);
DISPLAY 0.617021 (600 3925);
PAINT AQUA (600 3925);
FORCEPROP 1 LASTPIN (500 3850) $PN 1
J 0
(490 3865);
DISPLAY 0.617021 (490 3865);
PAINT ORANGE (490 3865);
FORCEPROP 1 LAST VALUE 0.22UF
J 2
(525 3800);
DISPLAY 0.617021 (525 3800);
PAINT SKYBLUE (525 3800);
FORCEPROP 2 LAST SEC 1
J 0
(600 4100);
DISPLAY 0.680851 (600 4100);
PAINT MONO (600 4100);
DISPLAY INVISIBLE (600 4100);
FORCEPROP 2 LAST SEC_TYPE 0402
J 0
(600 4100);
DISPLAY 1.021277 (600 4100);
PAINT ORANGE (600 4100);
DISPLAY INVISIBLE (600 4100);
FORCEPROP 0 LAST ROOM IO_SLOT
J 0
(600 4050);
DISPLAY 1.021277 (600 4050);
PAINT ORANGE (600 4050);
DISPLAY INVISIBLE (600 4050);
FORCEPROP 1 LAST PATH I167
J 0
(600 4050);
DISPLAY 0.978723 (600 4050);
PAINT WHITE (600 4050);
DISPLAY INVISIBLE (600 4050);
FORCEPROP 2 LAST CDS_LIB mstr_discrete
J 0
(600 3850);
PAINT ORANGE (600 3850);
DISPLAY INVISIBLE (600 3850);
FORCEPROP 0 LAST BOM_COST IO_SLOT
J 0
(600 4000);
DISPLAY 1.021277 (600 4000);
PAINT ORANGE (600 4000);
DISPLAY INVISIBLE (600 4000);
FORCEPROP 2 LAST CDS_LOCATION C1F3
J 1
(600 3925);
DISPLAY 0.617021 (600 3925);
PAINT AQUA (600 3925);
DISPLAY INVISIBLE (600 3925);
FORCEADD CAP..2
(600 3650);
FORCEPROP 1 LAST TOLERANCE 10%
J 2
(1025 3625);
DISPLAY 0.617021 (1025 3625);
PAINT SKYBLUE (1025 3625);
FORCEPROP 1 LAST PACK_TYPE 0402
J 1
(1125 3625);
DISPLAY 0.617021 (1125 3625);
PAINT SKYBLUE (1125 3625);
FORCEPROP 1 LAST MATERIAL X7R
J 0
(825 3625);
DISPLAY 0.617021 (825 3625);
PAINT SKYBLUE (825 3625);
FORCEPROP 1 LAST VOLTAGE 16V
J 0
(700 3625);
DISPLAY 0.617021 (700 3625);
PAINT SKYBLUE (700 3625);
FORCEPROP 1 LAST PART_NUMBER A36096-155
J 1
(800 3725);
DISPLAY 0.617021 (800 3725);
PAINT BLUE (800 3725);
FORCEPROP 1 LASTPIN (700 3650) $PN 2
J 0
(685 3665);
DISPLAY 0.617021 (685 3665);
PAINT ORANGE (685 3665);
FORCEPROP 1 LAST LOCATION C1F12
J 1
(600 3725);
DISPLAY 0.617021 (600 3725);
PAINT AQUA (600 3725);
FORCEPROP 1 LASTPIN (500 3650) $PN 1
J 0
(490 3665);
DISPLAY 0.617021 (490 3665);
PAINT ORANGE (490 3665);
FORCEPROP 1 LAST VALUE 0.22UF
J 2
(525 3600);
DISPLAY 0.617021 (525 3600);
PAINT SKYBLUE (525 3600);
FORCEPROP 0 LAST ROOM IO_SLOT
J 0
(600 3850);
DISPLAY 1.021277 (600 3850);
PAINT ORANGE (600 3850);
DISPLAY INVISIBLE (600 3850);
FORCEPROP 2 LAST SEC_TYPE 0402
J 0
(600 3900);
DISPLAY 1.021277 (600 3900);
PAINT ORANGE (600 3900);
DISPLAY INVISIBLE (600 3900);
FORCEPROP 2 LAST SEC 1
J 0
(600 3900);
DISPLAY 0.680851 (600 3900);
PAINT MONO (600 3900);
DISPLAY INVISIBLE (600 3900);
FORCEPROP 1 LAST PATH I168
J 0
(600 3850);
DISPLAY 0.978723 (600 3850);
PAINT WHITE (600 3850);
DISPLAY INVISIBLE (600 3850);
FORCEPROP 0 LAST BOM_COST IO_SLOT
J 0
(600 3800);
DISPLAY 1.021277 (600 3800);
PAINT ORANGE (600 3800);
DISPLAY INVISIBLE (600 3800);
FORCEPROP 2 LAST CDS_LIB mstr_discrete
J 0
(600 3650);
PAINT ORANGE (600 3650);
DISPLAY INVISIBLE (600 3650);
FORCEPROP 2 LAST CDS_LOCATION C1F12
J 1
(600 3725);
DISPLAY 0.617021 (600 3725);
PAINT AQUA (600 3725);
DISPLAY INVISIBLE (600 3725);
FORCEADD CAP..2
(600 3500);
FORCEPROP 1 LAST PART_NUMBER A36096-155
J 1
(850 3550);
DISPLAY 0.617021 (850 3550);
PAINT BLUE (850 3550);
FORCEPROP 1 LAST PACK_TYPE 0402
J 1
(1125 3475);
DISPLAY 0.617021 (1125 3475);
PAINT SKYBLUE (1125 3475);
FORCEPROP 1 LAST TOLERANCE 10%
J 2
(1025 3475);
DISPLAY 0.617021 (1025 3475);
PAINT SKYBLUE (1025 3475);
FORCEPROP 1 LAST LOCATION C1F11
J 1
(600 3575);
DISPLAY 0.617021 (600 3575);
PAINT AQUA (600 3575);
FORCEPROP 1 LAST MATERIAL X7R
J 0
(825 3475);
DISPLAY 0.617021 (825 3475);
PAINT SKYBLUE (825 3475);
FORCEPROP 1 LAST VOLTAGE 16V
J 0
(700 3475);
DISPLAY 0.617021 (700 3475);
PAINT SKYBLUE (700 3475);
FORCEPROP 1 LASTPIN (700 3500) $PN 2
J 0
(685 3515);
DISPLAY 0.617021 (685 3515);
PAINT ORANGE (685 3515);
FORCEPROP 1 LASTPIN (500 3500) $PN 1
J 0
(490 3515);
DISPLAY 0.617021 (490 3515);
PAINT ORANGE (490 3515);
FORCEPROP 1 LAST VALUE 0.22UF
J 2
(525 3450);
DISPLAY 0.617021 (525 3450);
PAINT SKYBLUE (525 3450);
FORCEPROP 0 LAST ROOM IO_SLOT
J 0
(600 3700);
DISPLAY 1.021277 (600 3700);
PAINT ORANGE (600 3700);
DISPLAY INVISIBLE (600 3700);
FORCEPROP 2 LAST SEC_TYPE 0402
J 0
(600 3750);
DISPLAY 1.021277 (600 3750);
PAINT ORANGE (600 3750);
DISPLAY INVISIBLE (600 3750);
FORCEPROP 0 LAST BOM_COST IO_SLOT
J 0
(600 3650);
DISPLAY 1.021277 (600 3650);
PAINT ORANGE (600 3650);
DISPLAY INVISIBLE (600 3650);
FORCEPROP 2 LAST SEC 1
J 0
(600 3750);
DISPLAY 0.680851 (600 3750);
PAINT MONO (600 3750);
DISPLAY INVISIBLE (600 3750);
FORCEPROP 1 LAST PATH I169
J 0
(600 3700);
DISPLAY 0.978723 (600 3700);
PAINT WHITE (600 3700);
DISPLAY INVISIBLE (600 3700);
FORCEPROP 2 LAST CDS_LOCATION C1F11
J 1
(600 3575);
DISPLAY 0.617021 (600 3575);
PAINT AQUA (600 3575);
DISPLAY INVISIBLE (600 3575);
FORCEPROP 2 LAST CDS_LIB mstr_discrete
J 0
(600 3500);
PAINT ORANGE (600 3500);
DISPLAY INVISIBLE (600 3500);
FORCEADD CAP..2
(600 3350);
FORCEPROP 1 LAST VALUE 0.22UF
J 2
(525 3300);
DISPLAY 0.617021 (525 3300);
PAINT SKYBLUE (525 3300);
FORCEPROP 1 LAST PACK_TYPE 0402
J 1
(1125 3325);
DISPLAY 0.617021 (1125 3325);
PAINT SKYBLUE (1125 3325);
FORCEPROP 1 LAST TOLERANCE 10%
J 2
(1025 3325);
DISPLAY 0.617021 (1025 3325);
PAINT SKYBLUE (1025 3325);
FORCEPROP 1 LAST MATERIAL X7R
J 0
(825 3325);
DISPLAY 0.617021 (825 3325);
PAINT SKYBLUE (825 3325);
FORCEPROP 1 LAST VOLTAGE 16V
J 0
(700 3325);
DISPLAY 0.617021 (700 3325);
PAINT SKYBLUE (700 3325);
FORCEPROP 1 LAST PART_NUMBER A36096-155
J 1
(800 3400);
DISPLAY 0.617021 (800 3400);
PAINT BLUE (800 3400);
FORCEPROP 1 LASTPIN (700 3350) $PN 2
J 0
(685 3365);
DISPLAY 0.617021 (685 3365);
PAINT ORANGE (685 3365);
FORCEPROP 1 LAST LOCATION C1F8
J 1
(600 3425);
DISPLAY 0.617021 (600 3425);
PAINT AQUA (600 3425);
FORCEPROP 1 LASTPIN (500 3350) $PN 1
J 0
(490 3365);
DISPLAY 0.617021 (490 3365);
PAINT ORANGE (490 3365);
FORCEPROP 2 LAST SEC 1
J 0
(600 3600);
DISPLAY 0.680851 (600 3600);
PAINT MONO (600 3600);
DISPLAY INVISIBLE (600 3600);
FORCEPROP 2 LAST SEC_TYPE 0402
J 0
(600 3600);
DISPLAY 1.021277 (600 3600);
PAINT ORANGE (600 3600);
DISPLAY INVISIBLE (600 3600);
FORCEPROP 1 LAST PATH I170
J 0
(600 3550);
DISPLAY 0.978723 (600 3550);
PAINT WHITE (600 3550);
DISPLAY INVISIBLE (600 3550);
FORCEPROP 0 LAST ROOM IO_SLOT
J 0
(600 3550);
DISPLAY 1.021277 (600 3550);
PAINT ORANGE (600 3550);
DISPLAY INVISIBLE (600 3550);
FORCEPROP 2 LAST CDS_LIB mstr_discrete
J 0
(600 3350);
PAINT ORANGE (600 3350);
DISPLAY INVISIBLE (600 3350);
FORCEPROP 0 LAST BOM_COST IO_SLOT
J 0
(600 3500);
DISPLAY 1.021277 (600 3500);
PAINT ORANGE (600 3500);
DISPLAY INVISIBLE (600 3500);
FORCEPROP 2 LAST CDS_LOCATION C1F8
J 1
(600 3425);
DISPLAY 0.617021 (600 3425);
PAINT AQUA (600 3425);
DISPLAY INVISIBLE (600 3425);
FORCEADD CAP..2
(550 3100);
FORCEPROP 1 LAST PACK_TYPE 0402
J 1
(1075 3075);
DISPLAY 0.617021 (1075 3075);
PAINT SKYBLUE (1075 3075);
FORCEPROP 1 LAST MATERIAL X7R
J 0
(775 3075);
DISPLAY 0.617021 (775 3075);
PAINT SKYBLUE (775 3075);
FORCEPROP 1 LAST TOLERANCE 10%
J 2
(975 3075);
DISPLAY 0.617021 (975 3075);
PAINT SKYBLUE (975 3075);
FORCEPROP 1 LAST PART_NUMBER A36096-155
J 1
(775 3175);
DISPLAY 0.617021 (775 3175);
PAINT BLUE (775 3175);
FORCEPROP 1 LASTPIN (650 3100) $PN 2
J 0
(635 3115);
DISPLAY 0.617021 (635 3115);
PAINT ORANGE (635 3115);
FORCEPROP 1 LAST VOLTAGE 16V
J 0
(650 3075);
DISPLAY 0.617021 (650 3075);
PAINT SKYBLUE (650 3075);
FORCEPROP 1 LAST LOCATION C1F18
J 1
(550 3175);
DISPLAY 0.617021 (550 3175);
PAINT AQUA (550 3175);
FORCEPROP 1 LASTPIN (450 3100) $PN 1
J 0
(440 3115);
DISPLAY 0.617021 (440 3115);
PAINT ORANGE (440 3115);
FORCEPROP 1 LAST VALUE 0.22UF
J 2
(475 3050);
DISPLAY 0.617021 (475 3050);
PAINT SKYBLUE (475 3050);
FORCEPROP 2 LAST SEC_TYPE 0402
J 0
(550 3350);
DISPLAY 1.021277 (550 3350);
PAINT ORANGE (550 3350);
DISPLAY INVISIBLE (550 3350);
FORCEPROP 2 LAST SEC 1
J 0
(550 3350);
DISPLAY 0.680851 (550 3350);
PAINT MONO (550 3350);
DISPLAY INVISIBLE (550 3350);
FORCEPROP 1 LAST PATH I171
J 0
(550 3300);
DISPLAY 0.978723 (550 3300);
PAINT WHITE (550 3300);
DISPLAY INVISIBLE (550 3300);
FORCEPROP 0 LAST ROOM IO_SLOT
J 0
(550 3300);
DISPLAY 1.021277 (550 3300);
PAINT ORANGE (550 3300);
DISPLAY INVISIBLE (550 3300);
FORCEPROP 2 LAST CDS_LOCATION C1F18
J 1
(550 3175);
DISPLAY 0.617021 (550 3175);
PAINT AQUA (550 3175);
DISPLAY INVISIBLE (550 3175);
FORCEPROP 2 LAST CDS_LIB mstr_discrete
J 0
(550 3100);
PAINT ORANGE (550 3100);
DISPLAY INVISIBLE (550 3100);
FORCEPROP 0 LAST BOM_COST IO_SLOT
J 0
(550 3250);
DISPLAY 1.021277 (550 3250);
PAINT ORANGE (550 3250);
DISPLAY INVISIBLE (550 3250);
FORCEADD CAP..2
(1050 3000);
FORCEPROP 1 LAST PACK_TYPE 0402
J 1
(1575 2975);
DISPLAY 0.617021 (1575 2975);
PAINT SKYBLUE (1575 2975);
FORCEPROP 1 LAST TOLERANCE 10%
J 2
(1475 2975);
DISPLAY 0.617021 (1475 2975);
PAINT SKYBLUE (1475 2975);
FORCEPROP 1 LAST MATERIAL X7R
J 0
(1275 2975);
DISPLAY 0.617021 (1275 2975);
PAINT SKYBLUE (1275 2975);
FORCEPROP 1 LAST PART_NUMBER A36096-155
J 1
(1350 3025);
DISPLAY 0.617021 (1350 3025);
PAINT BLUE (1350 3025);
FORCEPROP 1 LASTPIN (1150 3000) $PN 2
J 0
(1135 3015);
DISPLAY 0.617021 (1135 3015);
PAINT ORANGE (1135 3015);
FORCEPROP 1 LAST VOLTAGE 16V
J 0
(1150 2975);
DISPLAY 0.617021 (1150 2975);
PAINT SKYBLUE (1150 2975);
FORCEPROP 1 LAST LOCATION C1F16
J 1
(1050 3050);
DISPLAY 0.617021 (1050 3050);
PAINT AQUA (1050 3050);
FORCEPROP 1 LASTPIN (950 3000) $PN 1
J 0
(940 3015);
DISPLAY 0.617021 (940 3015);
PAINT ORANGE (940 3015);
FORCEPROP 1 LAST VALUE 0.22UF
J 2
(1000 2975);
DISPLAY 0.617021 (1000 2975);
PAINT SKYBLUE (1000 2975);
FORCEPROP 0 LAST ROOM IO_SLOT
J 0
(1050 3200);
DISPLAY 1.021277 (1050 3200);
PAINT ORANGE (1050 3200);
DISPLAY INVISIBLE (1050 3200);
FORCEPROP 0 LAST BOM_COST IO_SLOT
J 0
(1050 3150);
DISPLAY 1.021277 (1050 3150);
PAINT ORANGE (1050 3150);
DISPLAY INVISIBLE (1050 3150);
FORCEPROP 2 LAST SEC_TYPE 0402
J 0
(1050 3250);
DISPLAY 1.021277 (1050 3250);
PAINT ORANGE (1050 3250);
DISPLAY INVISIBLE (1050 3250);
FORCEPROP 2 LAST SEC 1
J 0
(1050 3250);
DISPLAY 0.680851 (1050 3250);
PAINT MONO (1050 3250);
DISPLAY INVISIBLE (1050 3250);
FORCEPROP 1 LAST PATH I172
J 0
(1050 3200);
DISPLAY 0.978723 (1050 3200);
PAINT WHITE (1050 3200);
DISPLAY INVISIBLE (1050 3200);
FORCEPROP 2 LAST CDS_LOCATION C1F16
J 1
(1050 3050);
DISPLAY 0.617021 (1050 3050);
PAINT AQUA (1050 3050);
DISPLAY INVISIBLE (1050 3050);
FORCEPROP 2 LAST CDS_LIB mstr_discrete
J 0
(1050 3000);
PAINT ORANGE (1050 3000);
DISPLAY INVISIBLE (1050 3000);
FORCEADD CAP..2
(550 2950);
FORCEPROP 1 LAST PACK_TYPE 0402
J 1
(1075 2925);
DISPLAY 0.617021 (1075 2925);
PAINT SKYBLUE (1075 2925);
FORCEPROP 1 LAST TOLERANCE 10%
J 2
(975 2925);
DISPLAY 0.617021 (975 2925);
PAINT SKYBLUE (975 2925);
FORCEPROP 1 LAST PART_NUMBER A36096-155
J 1
(775 3025);
DISPLAY 0.617021 (775 3025);
PAINT BLUE (775 3025);
FORCEPROP 1 LASTPIN (650 2950) $PN 2
J 0
(635 2965);
DISPLAY 0.617021 (635 2965);
PAINT ORANGE (635 2965);
FORCEPROP 1 LAST VOLTAGE 16V
J 0
(650 2925);
DISPLAY 0.617021 (650 2925);
PAINT SKYBLUE (650 2925);
FORCEPROP 1 LAST LOCATION C1F17
J 1
(550 3025);
DISPLAY 0.617021 (550 3025);
PAINT AQUA (550 3025);
FORCEPROP 1 LAST VALUE 0.22UF
J 2
(500 2900);
DISPLAY 0.617021 (500 2900);
PAINT SKYBLUE (500 2900);
FORCEPROP 1 LASTPIN (450 2950) $PN 1
J 0
(440 2965);
DISPLAY 0.617021 (440 2965);
PAINT ORANGE (440 2965);
FORCEPROP 1 LAST MATERIAL X7R
J 0
(775 2925);
DISPLAY 0.617021 (775 2925);
PAINT SKYBLUE (775 2925);
FORCEPROP 1 LAST PATH I173
J 0
(550 3150);
DISPLAY 0.978723 (550 3150);
PAINT WHITE (550 3150);
DISPLAY INVISIBLE (550 3150);
FORCEPROP 0 LAST BOM_COST IO_SLOT
J 0
(550 3100);
DISPLAY 1.021277 (550 3100);
PAINT ORANGE (550 3100);
DISPLAY INVISIBLE (550 3100);
FORCEPROP 2 LAST SEC_TYPE 0402
J 0
(550 3200);
DISPLAY 1.021277 (550 3200);
PAINT ORANGE (550 3200);
DISPLAY INVISIBLE (550 3200);
FORCEPROP 2 LAST SEC 1
J 0
(550 3200);
DISPLAY 0.680851 (550 3200);
PAINT MONO (550 3200);
DISPLAY INVISIBLE (550 3200);
FORCEPROP 0 LAST ROOM IO_SLOT
J 0
(550 3150);
DISPLAY 1.021277 (550 3150);
PAINT ORANGE (550 3150);
DISPLAY INVISIBLE (550 3150);
FORCEPROP 2 LAST CDS_LOCATION C1F17
J 1
(550 3025);
DISPLAY 0.617021 (550 3025);
PAINT AQUA (550 3025);
DISPLAY INVISIBLE (550 3025);
FORCEPROP 2 LAST CDS_LIB mstr_discrete
J 0
(550 2950);
PAINT ORANGE (550 2950);
DISPLAY INVISIBLE (550 2950);
FORCEADD CAP..2
(1050 2850);
FORCEPROP 1 LAST PACK_TYPE 0402
J 1
(1575 2825);
DISPLAY 0.617021 (1575 2825);
PAINT SKYBLUE (1575 2825);
FORCEPROP 1 LAST TOLERANCE 10%
J 2
(1475 2825);
DISPLAY 0.617021 (1475 2825);
PAINT SKYBLUE (1475 2825);
FORCEPROP 1 LAST PART_NUMBER A36096-155
J 1
(1350 2875);
DISPLAY 0.617021 (1350 2875);
PAINT BLUE (1350 2875);
FORCEPROP 1 LAST MATERIAL X7R
J 0
(1275 2825);
DISPLAY 0.617021 (1275 2825);
PAINT SKYBLUE (1275 2825);
FORCEPROP 1 LASTPIN (1150 2850) $PN 2
J 0
(1135 2865);
DISPLAY 0.617021 (1135 2865);
PAINT ORANGE (1135 2865);
FORCEPROP 1 LAST LOCATION C1F15
J 1
(1075 2900);
DISPLAY 0.617021 (1075 2900);
PAINT AQUA (1075 2900);
FORCEPROP 1 LASTPIN (950 2850) $PN 1
J 0
(940 2865);
DISPLAY 0.617021 (940 2865);
PAINT ORANGE (940 2865);
FORCEPROP 1 LAST VALUE 0.22UF
J 2
(1000 2825);
DISPLAY 0.617021 (1000 2825);
PAINT SKYBLUE (1000 2825);
FORCEPROP 1 LAST VOLTAGE 16V
J 0
(1150 2825);
DISPLAY 0.617021 (1150 2825);
PAINT SKYBLUE (1150 2825);
FORCEPROP 2 LAST SEC_TYPE 0402
J 0
(1050 3100);
DISPLAY 1.021277 (1050 3100);
PAINT ORANGE (1050 3100);
DISPLAY INVISIBLE (1050 3100);
FORCEPROP 2 LAST SEC 1
J 0
(1050 3100);
DISPLAY 0.680851 (1050 3100);
PAINT MONO (1050 3100);
DISPLAY INVISIBLE (1050 3100);
FORCEPROP 1 LAST PATH I174
J 0
(1050 3050);
DISPLAY 0.978723 (1050 3050);
PAINT WHITE (1050 3050);
DISPLAY INVISIBLE (1050 3050);
FORCEPROP 0 LAST ROOM IO_SLOT
J 0
(1050 3050);
DISPLAY 1.021277 (1050 3050);
PAINT ORANGE (1050 3050);
DISPLAY INVISIBLE (1050 3050);
FORCEPROP 2 LAST CDS_LIB mstr_discrete
J 0
(1050 2850);
PAINT ORANGE (1050 2850);
DISPLAY INVISIBLE (1050 2850);
FORCEPROP 0 LAST BOM_COST IO_SLOT
J 0
(1050 3000);
DISPLAY 1.021277 (1050 3000);
PAINT ORANGE (1050 3000);
DISPLAY INVISIBLE (1050 3000);
FORCEPROP 2 LAST CDS_LOCATION C1F15
J 1
(1075 2900);
DISPLAY 0.617021 (1075 2900);
PAINT AQUA (1075 2900);
DISPLAY INVISIBLE (1075 2900);
FORCEADD CAP..2
(550 2800);
FORCEPROP 1 LAST PACK_TYPE 0402
J 1
(1075 2775);
DISPLAY 0.617021 (1075 2775);
PAINT SKYBLUE (1075 2775);
FORCEPROP 1 LAST MATERIAL X7R
J 0
(775 2775);
DISPLAY 0.617021 (775 2775);
PAINT SKYBLUE (775 2775);
FORCEPROP 1 LAST TOLERANCE 10%
J 2
(975 2775);
DISPLAY 0.617021 (975 2775);
PAINT SKYBLUE (975 2775);
FORCEPROP 1 LAST PART_NUMBER A36096-155
J 1
(775 2875);
DISPLAY 0.617021 (775 2875);
PAINT BLUE (775 2875);
FORCEPROP 1 LASTPIN (650 2800) $PN 2
J 0
(635 2815);
DISPLAY 0.617021 (635 2815);
PAINT ORANGE (635 2815);
FORCEPROP 1 LAST VOLTAGE 16V
J 0
(650 2775);
DISPLAY 0.617021 (650 2775);
PAINT SKYBLUE (650 2775);
FORCEPROP 1 LAST LOCATION C1F14
J 1
(550 2875);
DISPLAY 0.617021 (550 2875);
PAINT AQUA (550 2875);
FORCEPROP 1 LAST VALUE 0.22UF
J 2
(500 2750);
DISPLAY 0.617021 (500 2750);
PAINT SKYBLUE (500 2750);
FORCEPROP 1 LASTPIN (450 2800) $PN 1
J 0
(440 2815);
DISPLAY 0.617021 (440 2815);
PAINT ORANGE (440 2815);
FORCEPROP 2 LAST SEC 1
J 0
(550 3050);
DISPLAY 0.680851 (550 3050);
PAINT MONO (550 3050);
DISPLAY INVISIBLE (550 3050);
FORCEPROP 2 LAST SEC_TYPE 0402
J 0
(550 3050);
DISPLAY 1.021277 (550 3050);
PAINT ORANGE (550 3050);
DISPLAY INVISIBLE (550 3050);
FORCEPROP 0 LAST ROOM IO_SLOT
J 0
(550 3000);
DISPLAY 1.021277 (550 3000);
PAINT ORANGE (550 3000);
DISPLAY INVISIBLE (550 3000);
FORCEPROP 0 LAST BOM_COST IO_SLOT
J 0
(550 2950);
DISPLAY 1.021277 (550 2950);
PAINT ORANGE (550 2950);
DISPLAY INVISIBLE (550 2950);
FORCEPROP 2 LAST CDS_LOCATION C1F14
J 1
(550 2875);
DISPLAY 0.617021 (550 2875);
PAINT AQUA (550 2875);
DISPLAY INVISIBLE (550 2875);
FORCEPROP 1 LAST PATH I175
J 0
(550 3000);
DISPLAY 0.978723 (550 3000);
PAINT WHITE (550 3000);
DISPLAY INVISIBLE (550 3000);
FORCEPROP 2 LAST CDS_LIB mstr_discrete
J 0
(550 2800);
PAINT ORANGE (550 2800);
DISPLAY INVISIBLE (550 2800);
FORCEADD P12V_PSU..1
(-2600 2325);
FORCEPROP 3 LASTPIN (-2600 2275) SIG_NAME P12V_PSU\g
J 0
(-2590 2285);
DISPLAY 0.659574 (-2590 2285);
PAINT MONO (-2590 2285);
DISPLAY INVISIBLE (-2590 2285);
FORCEPROP 1 LAST PATH I176
J 0
(-2550 2350);
DISPLAY 0.872340 (-2550 2350);
PAINT AQUA (-2550 2350);
DISPLAY INVISIBLE (-2550 2350);
FORCEPROP 2 LAST CDS_LIB mstr_symbols
J 0
(-2600 2325);
PAINT ORANGE (-2600 2325);
DISPLAY INVISIBLE (-2600 2325);
FORCEPROP 2 LAST BOM_COST NT_BASE_VRD
J 0
(-2600 2425);
DISPLAY 0.617021 (-2600 2425);
PAINT ORANGE (-2600 2425);
DISPLAY INVISIBLE (-2600 2425);
FORCEPROP 2 LAST ROOM P2V5_LAN_AUX_VR
J 0
(-2600 2425);
DISPLAY 0.617021 (-2600 2425);
PAINT ORANGE (-2600 2425);
DISPLAY INVISIBLE (-2600 2425);
FORCEPROP 1 LAST HDL_POWER P12V_PSU
J 1
(-2600 2375);
DISPLAY 0.872340 (-2600 2375);
PAINT GREEN (-2600 2375);
DISPLAY INVISIBLE (-2600 2375);
FORCEPROP 1 LAST BODY_TYPE PLUMBING
J 0
(-2645 2282);
DISPLAY 0.340426 (-2645 2282);
PAINT GREEN (-2645 2282);
DISPLAY INVISIBLE (-2645 2282);
FORCEPROP 1 LAST VOLTAGE 12.0
J 0
(-2645 2282);
DISPLAY 0.340426 (-2645 2282);
PAINT SKYBLUE (-2645 2282);
DISPLAY INVISIBLE (-2645 2282);
FORCEADD RES..2
(-2600 2100);
FORCEPROP 1 LAST PACK_TYPE 0402
J 0
(-2560 1925);
DISPLAY 0.617021 (-2560 1925);
PAINT SKYBLUE (-2560 1925);
FORCEPROP 1 LAST PART_NUMBER G21796-072
J 0
(-2560 1975);
DISPLAY 0.617021 (-2560 1975);
PAINT BLUE (-2560 1975);
FORCEPROP 1 LAST MATERIAL CHIP
J 0
(-2560 2025);
DISPLAY 0.617021 (-2560 2025);
PAINT SKYBLUE (-2560 2025);
FORCEPROP 1 LAST TOLERANCE 1%
J 0
(-2555 2125);
DISPLAY 0.617021 (-2555 2125);
PAINT SKYBLUE (-2555 2125);
FORCEPROP 1 LAST VALUE 4.75K
J 0
(-2555 2175);
DISPLAY 0.617021 (-2555 2175);
PAINT SKYBLUE (-2555 2175);
FORCEPROP 1 LAST WATTAGE 1/16W
J 0
(-2560 2075);
DISPLAY 0.617021 (-2560 2075);
PAINT SKYBLUE (-2560 2075);
FORCEPROP 1 LASTPIN (-2600 2200) $PN 1
J 0
(-2595 2162);
DISPLAY 0.617021 (-2595 2162);
PAINT ORANGE (-2595 2162);
FORCEPROP 1 LASTPIN (-2600 2000) $PN 2
J 0
(-2595 2010);
DISPLAY 0.617021 (-2595 2010);
PAINT ORANGE (-2595 2010);
FORCEPROP 1 LAST LOCATION R9T9
J 0
(-2555 2225);
DISPLAY 0.617021 (-2555 2225);
PAINT AQUA (-2555 2225);
FORCEPROP 1 LAST PATH I177
J 0
(-2550 2275);
DISPLAY 0.978723 (-2550 2275);
PAINT WHITE (-2550 2275);
DISPLAY INVISIBLE (-2550 2275);
FORCEPROP 2 LAST CDS_LOCATION R9T9
J 0
(-2555 2225);
DISPLAY 0.617021 (-2555 2225);
PAINT AQUA (-2555 2225);
DISPLAY INVISIBLE (-2555 2225);
FORCEPROP 2 LAST SEC 1
J 0
(-2550 2325);
DISPLAY 0.680851 (-2550 2325);
PAINT MONO (-2550 2325);
DISPLAY INVISIBLE (-2550 2325);
FORCEPROP 2 LAST SEC_TYPE 0402
J 0
(-2550 2325);
DISPLAY 1.021277 (-2550 2325);
PAINT ORANGE (-2550 2325);
DISPLAY INVISIBLE (-2550 2325);
FORCEPROP 0 LAST BOM_COST IO_SLOT
J 0
(-2550 2425);
DISPLAY 1.021277 (-2550 2425);
PAINT ORANGE (-2550 2425);
DISPLAY INVISIBLE (-2550 2425);
FORCEPROP 0 LAST ROOM IO_SLOT
J 0
(-2550 2325);
DISPLAY 1.021277 (-2550 2325);
PAINT ORANGE (-2550 2325);
DISPLAY INVISIBLE (-2550 2325);
FORCEPROP 2 LAST CDS_LIB mstr_discrete
J 0
(-2600 2100);
PAINT MONO (-2600 2100);
DISPLAY INVISIBLE (-2600 2100);
FORCEADD DIODE..1
(-2275 1800);
FORCEPROP 1 LAST VALUE SDMK0340L
J 0
(-2300 1675);
DISPLAY 0.617021 (-2300 1675);
PAINT SKYBLUE (-2300 1675);
FORCEPROP 1 LAST PACK_TYPE SM
J 0
(-2300 1560);
DISPLAY 0.617021 (-2300 1560);
PAINT SKYBLUE (-2300 1560);
FORCEPROP 1 LAST MATERIAL IC
J 0
(-2300 1622);
DISPLAY 0.617021 (-2300 1622);
PAINT SKYBLUE (-2300 1622);
FORCEPROP 1 LAST PART_NUMBER H71799-001
J 0
(-2300 1900);
DISPLAY 0.617021 (-2300 1900);
PAINT BLUE (-2300 1900);
FORCEPROP 1 LASTPIN (-2175 1800) $PN 1
J 0
(-2210 1810);
DISPLAY 0.617021 (-2210 1810);
PAINT AQUA (-2210 1810);
FORCEPROP 1 LAST LOCATION CR1F4
J 0
(-2302 1956);
DISPLAY 0.617021 (-2302 1956);
PAINT AQUA (-2302 1956);
FORCEPROP 1 LASTPIN (-2375 1800) $PN 2
J 2
(-2340 1810);
DISPLAY 0.617021 (-2340 1810);
PAINT AQUA (-2340 1810);
FORCEPROP 2 LAST SEC 1
J 0
(-2275 2075);
DISPLAY 0.680851 (-2275 2075);
PAINT MONO (-2275 2075);
DISPLAY INVISIBLE (-2275 2075);
FORCEPROP 2 LAST SEC_TYPE SM
J 0
(-2275 2075);
DISPLAY 1.021277 (-2275 2075);
PAINT ORANGE (-2275 2075);
DISPLAY INVISIBLE (-2275 2075);
FORCEPROP 0 LAST BOM_COST IO_SLOT
J 0
(-2300 2150);
DISPLAY 1.021277 (-2300 2150);
PAINT ORANGE (-2300 2150);
DISPLAY INVISIBLE (-2300 2150);
FORCEPROP 0 LAST ROOM IO_SLOT
J 0
(-2300 2050);
DISPLAY 1.021277 (-2300 2050);
PAINT ORANGE (-2300 2050);
DISPLAY INVISIBLE (-2300 2050);
FORCEPROP 1 LAST PATH I178
J 0
(-2295 2010);
DISPLAY 0.978723 (-2295 2010);
PAINT PINK (-2295 2010);
DISPLAY INVISIBLE (-2295 2010);
FORCEPROP 2 LAST CDS_LIB mstr_discrete
J 0
(-2275 1800);
PAINT ORANGE (-2275 1800);
DISPLAY INVISIBLE (-2275 1800);
FORCEPROP 2 LAST CDS_LOCATION CR1F4
J 0
(-2302 1956);
DISPLAY 0.617021 (-2302 1956);
PAINT AQUA (-2302 1956);
DISPLAY INVISIBLE (-2302 1956);
FORCEADD OFFPAGE..1
(-3450 1800);
FORCEPROP 2 LAST $XR0 181 
J 0
(-3702 1800);
DISPLAY 0.638298 (-3702 1800);
PAINT MONO (-3702 1800);
FORCEPROP 1 LAST OFFPAGE TRUE
J 0
(-3125 1675);
DISPLAY 0.872340 (-3125 1675);
PAINT GREEN (-3125 1675);
DISPLAY INVISIBLE (-3125 1675);
FORCEPROP 1 LAST COMMENT_BODY TRUE
J 0
(-3325 1700);
DISPLAY 0.872340 (-3325 1700);
PAINT GREEN (-3325 1700);
DISPLAY INVISIBLE (-3325 1700);
FORCEPROP 2 LAST CDS_LIB mstr_standard
J 0
(-3450 1800);
PAINT ORANGE (-3450 1800);
DISPLAY INVISIBLE (-3450 1800);
FORCEPROP 2 LAST PATH I179
J 0
(-3400 1875);
DISPLAY 1.021277 (-3400 1875);
PAINT ORANGE (-3400 1875);
DISPLAY INVISIBLE (-3400 1875);
FORCEADD DIODE..1
(-1025 1800);
FORCEPROP 1 LAST PACK_TYPE SM
J 0
(-1050 1560);
DISPLAY 0.617021 (-1050 1560);
PAINT SKYBLUE (-1050 1560);
FORCEPROP 1 LASTPIN (-925 1800) $PN 1
J 0
(-960 1810);
DISPLAY 0.617021 (-960 1810);
PAINT AQUA (-960 1810);
FORCEPROP 1 LAST MATERIAL IC
J 0
(-1050 1622);
DISPLAY 0.617021 (-1050 1622);
PAINT SKYBLUE (-1050 1622);
FORCEPROP 1 LAST VALUE SDMK0340L
J 0
(-1050 1675);
DISPLAY 0.617021 (-1050 1675);
PAINT SKYBLUE (-1050 1675);
FORCEPROP 1 LAST PART_NUMBER H71799-001
J 0
(-1050 1900);
DISPLAY 0.617021 (-1050 1900);
PAINT BLUE (-1050 1900);
FORCEPROP 1 LASTPIN (-1125 1800) $PN 2
J 2
(-1090 1810);
DISPLAY 0.617021 (-1090 1810);
PAINT AQUA (-1090 1810);
FORCEPROP 1 LAST LOCATION CR1F3
J 0
(-1052 1956);
DISPLAY 0.617021 (-1052 1956);
PAINT AQUA (-1052 1956);
FORCEPROP 0 LAST ROOM IO_SLOT
J 0
(-1050 2050);
DISPLAY 1.021277 (-1050 2050);
PAINT ORANGE (-1050 2050);
DISPLAY INVISIBLE (-1050 2050);
FORCEPROP 2 LAST SEC_TYPE SM
J 0
(-1025 2075);
DISPLAY 1.021277 (-1025 2075);
PAINT ORANGE (-1025 2075);
DISPLAY INVISIBLE (-1025 2075);
FORCEPROP 0 LAST BOM_COST IO_SLOT
J 0
(-1050 2150);
DISPLAY 1.021277 (-1050 2150);
PAINT ORANGE (-1050 2150);
DISPLAY INVISIBLE (-1050 2150);
FORCEPROP 2 LAST SEC 1
J 0
(-1025 2075);
DISPLAY 0.680851 (-1025 2075);
PAINT MONO (-1025 2075);
DISPLAY INVISIBLE (-1025 2075);
FORCEPROP 1 LAST PATH I180
J 0
(-1045 2010);
DISPLAY 0.978723 (-1045 2010);
PAINT PINK (-1045 2010);
DISPLAY INVISIBLE (-1045 2010);
FORCEPROP 2 LAST CDS_LOCATION CR1F3
J 0
(-1052 1956);
DISPLAY 0.617021 (-1052 1956);
PAINT AQUA (-1052 1956);
DISPLAY INVISIBLE (-1052 1956);
FORCEPROP 2 LAST CDS_LIB mstr_discrete
J 0
(-1025 1800);
PAINT ORANGE (-1025 1800);
DISPLAY INVISIBLE (-1025 1800);
FORCEADD NPN..1
(50 1800);
FORCEPROP 1 LAST MATERIAL IC
J 0
(200 1750);
DISPLAY 0.617021 (200 1750);
PAINT SKYBLUE (200 1750);
FORCEPROP 1 LAST PACK_TYPE SM
J 0
(200 1700);
DISPLAY 0.617021 (200 1700);
PAINT SKYBLUE (200 1700);
FORCEPROP 1 LAST VALUE MMBT3904
J 0
(200 1800);
DISPLAY 0.617021 (200 1800);
PAINT SKYBLUE (200 1800);
FORCEPROP 1 LAST PART_NUMBER C52245-001
J 0
(200 1650);
DISPLAY 0.617021 (200 1650);
PAINT BLUE (200 1650);
FORCEPROP 1 LAST LOCATION Q9T1
J 0
(200 1850);
DISPLAY 0.617021 (200 1850);
PAINT AQUA (200 1850);
FORCEPROP 1 LASTPIN (100 1900) $PN 3
J 0
(119 1910);
DISPLAY 0.617021 (119 1910);
PAINT GREEN (119 1910);
FORCEPROP 1 LASTPIN (100 1700) $PN 2
J 0
(125 1650);
DISPLAY 0.617021 (125 1650);
PAINT GREEN (125 1650);
FORCEPROP 1 LASTPIN (-50 1800) $PN 1
J 0
(-105 1825);
DISPLAY 0.617021 (-105 1825);
PAINT GREEN (-105 1825);
FORCEPROP 2 LAST ROOM SB
J 0
(200 1900);
DISPLAY 1.404255 (200 1900);
PAINT ORANGE (200 1900);
DISPLAY INVISIBLE (200 1900);
FORCEPROP 2 LAST SEC_TYPE SM
J 0
(200 1950);
DISPLAY 1.021277 (200 1950);
PAINT ORANGE (200 1950);
DISPLAY INVISIBLE (200 1950);
FORCEPROP 2 LAST SEC 1
J 0
(200 1950);
DISPLAY 0.680851 (200 1950);
PAINT MONO (200 1950);
DISPLAY INVISIBLE (200 1950);
FORCEPROP 2 LAST CDS_LOCATION Q9T1
J 0
(200 1850);
DISPLAY 0.617021 (200 1850);
PAINT AQUA (200 1850);
DISPLAY INVISIBLE (200 1850);
FORCEPROP 1 LAST PATH I181
J 0
(200 1900);
DISPLAY 0.978723 (200 1900);
PAINT BLUE (200 1900);
DISPLAY INVISIBLE (200 1900);
FORCEPROP 2 LAST CDS_LIB mstr_discrete
J 0
(50 1800);
PAINT ORANGE (50 1800);
DISPLAY INVISIBLE (50 1800);
FORCEADD GND..1
(100 1525);
FORCEPROP 3 LASTPIN (100 1575) SIG_NAME GND\g
J 0
(110 1585);
DISPLAY 0.659574 (110 1585);
PAINT MONO (110 1585);
DISPLAY INVISIBLE (110 1585);
FORCEPROP 1 LAST HDL_POWER GND
J 0
(100 1675);
DISPLAY 0.872340 (100 1675);
PAINT GREEN (100 1675);
DISPLAY INVISIBLE (100 1675);
FORCEPROP 1 LAST PATH I182
J 0
(175 1525);
DISPLAY 0.872340 (175 1525);
PAINT AQUA (175 1525);
DISPLAY INVISIBLE (175 1525);
FORCEPROP 2 LAST CDS_LIB mstr_symbols
J 0
(100 1525);
PAINT ORANGE (100 1525);
DISPLAY INVISIBLE (100 1525);
FORCEPROP 1 LAST VOLTAGE 0
J 0
(100 1525);
PAINT SKYBLUE (100 1525);
DISPLAY INVISIBLE (100 1525);
FORCEPROP 1 LAST BODY_TYPE PLUMBING
J 0
(55 1482);
DISPLAY 0.340426 (55 1482);
PAINT GREEN (55 1482);
DISPLAY INVISIBLE (55 1482);
FORCEPROP 1 LAST SIZE 1B
J 0
(175 1475);
DISPLAY 0.872340 (175 1475);
PAINT GREEN (175 1475);
DISPLAY INVISIBLE (175 1475);
FORCEPROP 2 LAST ROOM P2V5_LAN_AUX_VR
J 0
(-200 1600);
DISPLAY 0.617021 (-200 1600);
PAINT ORANGE (-200 1600);
DISPLAY INVISIBLE (-200 1600);
FORCEPROP 2 LAST BOM_COST NT_BASE_VRD
J 0
(-200 1600);
DISPLAY 0.617021 (-200 1600);
PAINT ORANGE (-200 1600);
DISPLAY INVISIBLE (-200 1600);
FORCEADD RES..2
R 2
(450 2150);
FORCEPROP 1 LASTPIN (450 2250) $PN 1
J 2
(445 2212);
DISPLAY 0.617021 (445 2212);
PAINT ORANGE (445 2212);
FORCEPROP 1 LASTPIN (450 2050) $PN 2
J 2
(445 2060);
DISPLAY 0.617021 (445 2060);
PAINT ORANGE (445 2060);
FORCEPROP 1 LAST WATTAGE 1/16W
J 2
(410 2125);
DISPLAY 0.617021 (410 2125);
PAINT SKYBLUE (410 2125);
FORCEPROP 1 LAST LOCATION R9T6
J 2
(405 2275);
DISPLAY 0.617021 (405 2275);
PAINT AQUA (405 2275);
FORCEPROP 1 LAST VALUE 15.0K
J 2
(405 2225);
DISPLAY 0.617021 (405 2225);
PAINT SKYBLUE (405 2225);
FORCEPROP 1 LAST TOLERANCE 1%
J 2
(405 2175);
DISPLAY 0.617021 (405 2175);
PAINT SKYBLUE (405 2175);
FORCEPROP 1 LAST PACK_TYPE 0402
J 2
(285 2075);
DISPLAY 0.617021 (285 2075);
PAINT SKYBLUE (285 2075);
FORCEPROP 1 LAST MATERIAL CHIP
J 2
(410 2075);
DISPLAY 0.617021 (410 2075);
PAINT SKYBLUE (410 2075);
FORCEPROP 1 LAST PART_NUMBER G21796-107
J 2
(410 2025);
DISPLAY 0.617021 (410 2025);
PAINT BLUE (410 2025);
FORCEPROP 1 LAST PATH I183
J 2
(400 2325);
DISPLAY 0.978723 (400 2325);
PAINT WHITE (400 2325);
DISPLAY INVISIBLE (400 2325);
FORCEPROP 2 LAST SEC 1
J 2
(400 2375);
DISPLAY 0.680851 (400 2375);
PAINT MONO (400 2375);
DISPLAY INVISIBLE (400 2375);
FORCEPROP 0 LAST BOM_COST IO_SLOT
J 2
(400 2475);
DISPLAY 1.021277 (400 2475);
PAINT ORANGE (400 2475);
DISPLAY INVISIBLE (400 2475);
FORCEPROP 2 LAST SEC_TYPE 0402
J 2
(400 2375);
DISPLAY 1.021277 (400 2375);
PAINT ORANGE (400 2375);
DISPLAY INVISIBLE (400 2375);
FORCEPROP 0 LAST ROOM IO_SLOT
J 2
(400 2375);
DISPLAY 1.021277 (400 2375);
PAINT ORANGE (400 2375);
DISPLAY INVISIBLE (400 2375);
FORCEPROP 2 LAST CDS_LOCATION R9T6
J 2
(405 2275);
DISPLAY 0.617021 (405 2275);
PAINT AQUA (405 2275);
DISPLAY INVISIBLE (405 2275);
FORCEPROP 2 LAST CDS_LIB mstr_discrete
J 2
(450 2150);
PAINT ORANGE (450 2150);
DISPLAY INVISIBLE (450 2150);
FORCEADD P12V_PSU..1
(450 2350);
FORCEPROP 3 LASTPIN (450 2300) SIG_NAME P12V_PSU\g
J 0
(460 2310);
DISPLAY 0.659574 (460 2310);
PAINT MONO (460 2310);
DISPLAY INVISIBLE (460 2310);
FORCEPROP 1 LAST PATH I184
J 0
(500 2375);
DISPLAY 0.872340 (500 2375);
PAINT AQUA (500 2375);
DISPLAY INVISIBLE (500 2375);
FORCEPROP 1 LAST BODY_TYPE PLUMBING
J 0
(405 2307);
DISPLAY 0.340426 (405 2307);
PAINT GREEN (405 2307);
DISPLAY INVISIBLE (405 2307);
FORCEPROP 2 LAST CDS_LIB mstr_symbols
J 0
(450 2350);
PAINT ORANGE (450 2350);
DISPLAY INVISIBLE (450 2350);
FORCEPROP 2 LAST BOM_COST NT_BASE_VRD
J 0
(450 2450);
DISPLAY 0.617021 (450 2450);
PAINT ORANGE (450 2450);
DISPLAY INVISIBLE (450 2450);
FORCEPROP 2 LAST ROOM P2V5_LAN_AUX_VR
J 0
(450 2450);
DISPLAY 0.617021 (450 2450);
PAINT ORANGE (450 2450);
DISPLAY INVISIBLE (450 2450);
FORCEPROP 1 LAST HDL_POWER P12V_PSU
J 1
(450 2400);
DISPLAY 0.872340 (450 2400);
PAINT GREEN (450 2400);
DISPLAY INVISIBLE (450 2400);
FORCEPROP 1 LAST VOLTAGE 12.0
J 0
(405 2307);
DISPLAY 0.340426 (405 2307);
PAINT SKYBLUE (405 2307);
DISPLAY INVISIBLE (405 2307);
FORCEADD RES..2
(550 1800);
FORCEPROP 1 LAST PART_NUMBER G21796-161
J 0
(590 1675);
DISPLAY 0.617021 (590 1675);
PAINT BLUE (590 1675);
FORCEPROP 1 LAST LOCATION R9T3
J 0
(595 1925);
DISPLAY 0.617021 (595 1925);
PAINT AQUA (595 1925);
FORCEPROP 1 LAST VALUE 6.19K
J 0
(595 1875);
DISPLAY 0.617021 (595 1875);
PAINT SKYBLUE (595 1875);
FORCEPROP 1 LAST TOLERANCE 1%
J 0
(595 1825);
DISPLAY 0.617021 (595 1825);
PAINT SKYBLUE (595 1825);
FORCEPROP 1 LASTPIN (550 1900) $PN 1
J 0
(555 1862);
DISPLAY 0.617021 (555 1862);
PAINT ORANGE (555 1862);
FORCEPROP 1 LAST WATTAGE 1/16W
J 0
(590 1775);
DISPLAY 0.617021 (590 1775);
PAINT SKYBLUE (590 1775);
FORCEPROP 1 LASTPIN (550 1700) $PN 2
J 0
(555 1710);
DISPLAY 0.617021 (555 1710);
PAINT ORANGE (555 1710);
FORCEPROP 1 LAST MATERIAL CHIP
J 0
(590 1725);
DISPLAY 0.617021 (590 1725);
PAINT SKYBLUE (590 1725);
FORCEPROP 1 LAST PACK_TYPE 0402
J 0
(590 1625);
DISPLAY 0.617021 (590 1625);
PAINT SKYBLUE (590 1625);
FORCEPROP 0 LAST BOM_COST IO_SLOT
J 0
(600 2125);
DISPLAY 1.021277 (600 2125);
PAINT ORANGE (600 2125);
DISPLAY INVISIBLE (600 2125);
FORCEPROP 2 LAST SEC 1
J 0
(600 2025);
DISPLAY 0.680851 (600 2025);
PAINT MONO (600 2025);
DISPLAY INVISIBLE (600 2025);
FORCEPROP 2 LAST SEC_TYPE 0402
J 0
(600 2025);
DISPLAY 1.021277 (600 2025);
PAINT ORANGE (600 2025);
DISPLAY INVISIBLE (600 2025);
FORCEPROP 0 LAST ROOM IO_SLOT
J 0
(600 2025);
DISPLAY 1.021277 (600 2025);
PAINT ORANGE (600 2025);
DISPLAY INVISIBLE (600 2025);
FORCEPROP 1 LAST PATH I185
J 0
(600 1975);
DISPLAY 0.978723 (600 1975);
PAINT WHITE (600 1975);
DISPLAY INVISIBLE (600 1975);
FORCEPROP 2 LAST CDS_LOCATION R9T3
J 0
(595 1925);
DISPLAY 0.617021 (595 1925);
PAINT AQUA (595 1925);
DISPLAY INVISIBLE (595 1925);
FORCEPROP 2 LAST CDS_LIB mstr_discrete
J 0
(550 1800);
PAINT ORANGE (550 1800);
DISPLAY INVISIBLE (550 1800);
FORCEADD GND..1
(550 1500);
FORCEPROP 3 LASTPIN (550 1550) SIG_NAME GND\g
J 0
(560 1560);
DISPLAY 0.659574 (560 1560);
PAINT MONO (560 1560);
DISPLAY INVISIBLE (560 1560);
FORCEPROP 1 LAST HDL_POWER GND
J 0
(550 1650);
DISPLAY 0.872340 (550 1650);
PAINT GREEN (550 1650);
DISPLAY INVISIBLE (550 1650);
FORCEPROP 1 LAST PATH I186
J 0
(625 1500);
DISPLAY 0.872340 (625 1500);
PAINT AQUA (625 1500);
DISPLAY INVISIBLE (625 1500);
FORCEPROP 2 LAST CDS_LIB mstr_symbols
J 0
(550 1500);
PAINT ORANGE (550 1500);
DISPLAY INVISIBLE (550 1500);
FORCEPROP 1 LAST VOLTAGE 0
J 0
(550 1500);
PAINT SKYBLUE (550 1500);
DISPLAY INVISIBLE (550 1500);
FORCEPROP 1 LAST SIZE 1B
J 0
(625 1450);
DISPLAY 0.872340 (625 1450);
PAINT GREEN (625 1450);
DISPLAY INVISIBLE (625 1450);
FORCEPROP 2 LAST ROOM P2V5_LAN_AUX_VR
J 0
(250 1575);
DISPLAY 0.617021 (250 1575);
PAINT ORANGE (250 1575);
DISPLAY INVISIBLE (250 1575);
FORCEPROP 2 LAST BOM_COST NT_BASE_VRD
J 0
(250 1575);
DISPLAY 0.617021 (250 1575);
PAINT ORANGE (250 1575);
DISPLAY INVISIBLE (250 1575);
FORCEPROP 1 LAST BODY_TYPE PLUMBING
J 0
(505 1457);
DISPLAY 0.340426 (505 1457);
PAINT GREEN (505 1457);
DISPLAY INVISIBLE (505 1457);
FORCEADD OFFPAGE..2
(1175 2000);
FORCEPROP 2 LAST $XR0 199 
J 0
(1364 2000);
DISPLAY 0.638298 (1364 2000);
PAINT MONO (1364 2000);
FORCEPROP 2 LAST PATH I187
J 0
(1350 2075);
DISPLAY 1.021277 (1350 2075);
PAINT ORANGE (1350 2075);
DISPLAY INVISIBLE (1350 2075);
FORCEPROP 1 LAST OFFPAGE TRUE
J 0
(1500 1875);
DISPLAY 0.872340 (1500 1875);
PAINT GREEN (1500 1875);
DISPLAY INVISIBLE (1500 1875);
FORCEPROP 1 LAST COMMENT_BODY TRUE
J 0
(1130 1905);
DISPLAY 0.872340 (1130 1905);
PAINT GREEN (1130 1905);
DISPLAY INVISIBLE (1130 1905);
FORCEPROP 2 LAST CDS_LIB mstr_standard
J 0
(1175 2000);
PAINT ORANGE (1175 2000);
DISPLAY INVISIBLE (1175 2000);
FORCEADD CONN8_H62179001..1
(3500 1500);
FORCEPROP 1 LAST PART_NUMBER H62179-001
J 0
(3350 1150);
DISPLAY 0.617021 (3350 1150);
PAINT BLUE (3350 1150);
FORCEPROP 1 LAST LOCATION J1F3
J 0
(3400 1925);
DISPLAY 0.617021 (3400 1925);
PAINT AQUA (3400 1925);
FORCEPROP 1 LAST MATERIAL CONN
J 0
(3350 1850);
DISPLAY 0.617021 (3350 1850);
PAINT SKYBLUE (3350 1850);
FORCEPROP 2 LASTPIN (3300 1550) $PN 2
J 2
(3290 1560);
DISPLAY 0.617021 (3290 1560);
PAINT MONO (3290 1560);
FORCEPROP 2 LASTPIN (3300 1600) $PN 1
J 2
(3290 1610);
DISPLAY 0.617021 (3290 1610);
PAINT MONO (3290 1610);
FORCEPROP 2 LASTPIN (3300 1300) $PN 7
J 2
(3290 1310);
DISPLAY 0.617021 (3290 1310);
PAINT MONO (3290 1310);
FORCEPROP 2 LASTPIN (3300 1350) $PN 6
J 2
(3290 1360);
DISPLAY 0.617021 (3290 1360);
PAINT MONO (3290 1360);
FORCEPROP 2 LASTPIN (3300 1400) $PN 5
J 2
(3290 1410);
DISPLAY 0.617021 (3290 1410);
PAINT MONO (3290 1410);
FORCEPROP 2 LASTPIN (3300 1450) $PN 4
J 2
(3290 1460);
DISPLAY 0.617021 (3290 1460);
PAINT MONO (3290 1460);
FORCEPROP 2 LASTPIN (3300 1500) $PN 3
J 2
(3290 1510);
DISPLAY 0.617021 (3290 1510);
PAINT MONO (3290 1510);
FORCEPROP 2 LASTPIN (3300 1250) $PN 8
J 2
(3290 1260);
DISPLAY 0.617021 (3290 1260);
PAINT MONO (3290 1260);
FORCEPROP 1 LAST PACK_TYPE PIP
J 0
(3350 1950);
PAINT SKYBLUE (3350 1950);
DISPLAY INVISIBLE (3350 1950);
FORCEPROP 0 LAST ROOM IO_SLOT
J 2
(3450 1975);
DISPLAY 0.617021 (3450 1975);
PAINT ORANGE (3450 1975);
DISPLAY INVISIBLE (3450 1975);
FORCEPROP 1 LAST PATH I189
J 0
(3525 1850);
PAINT GREEN (3525 1850);
DISPLAY INVISIBLE (3525 1850);
FORCEPROP 2 LAST CDS_LOCATION J1F3
J 0
(3400 1925);
DISPLAY 0.617021 (3400 1925);
PAINT AQUA (3400 1925);
DISPLAY INVISIBLE (3400 1925);
FORCEPROP 2 LAST $SEC 1
J 0
(3400 1975);
PAINT MONO (3400 1975);
DISPLAY INVISIBLE (3400 1975);
FORCEPROP 2 LAST CDS_SEC 1
J 0
(3400 1975);
PAINT MONO (3400 1975);
DISPLAY INVISIBLE (3400 1975);
FORCEPROP 2 LAST CDS_LIB mstr_conn
J 0
(3500 1500);
PAINT ORANGE (3500 1500);
DISPLAY INVISIBLE (3500 1500);
FORCEADD GND..1
(3050 1050);
FORCEPROP 3 LASTPIN (3050 1100) SIG_NAME GND\g
J 0
(3060 1110);
DISPLAY 0.659574 (3060 1110);
PAINT MONO (3060 1110);
DISPLAY INVISIBLE (3060 1110);
FORCEPROP 1 LAST PATH I191
J 0
(3125 1050);
DISPLAY 0.872340 (3125 1050);
PAINT AQUA (3125 1050);
DISPLAY INVISIBLE (3125 1050);
FORCEPROP 1 LAST SIZE 1B
J 0
(3125 1000);
DISPLAY 0.872340 (3125 1000);
PAINT GREEN (3125 1000);
DISPLAY INVISIBLE (3125 1000);
FORCEPROP 1 LAST VOLTAGE 0
J 0
(3050 1050);
PAINT SKYBLUE (3050 1050);
DISPLAY INVISIBLE (3050 1050);
FORCEPROP 1 LAST HDL_POWER GND
J 0
(3050 1200);
DISPLAY 0.872340 (3050 1200);
PAINT GREEN (3050 1200);
DISPLAY INVISIBLE (3050 1200);
FORCEPROP 2 LAST CDS_LIB mstr_symbols
J 0
(3050 1050);
PAINT ORANGE (3050 1050);
DISPLAY INVISIBLE (3050 1050);
FORCEPROP 2 LAST ROOM P2V5_LAN_AUX_VR
J 0
(2750 1125);
DISPLAY 0.617021 (2750 1125);
PAINT ORANGE (2750 1125);
DISPLAY INVISIBLE (2750 1125);
FORCEPROP 2 LAST BOM_COST NT_BASE_VRD
J 0
(2750 1125);
DISPLAY 0.617021 (2750 1125);
PAINT ORANGE (2750 1125);
DISPLAY INVISIBLE (2750 1125);
FORCEPROP 1 LAST BODY_TYPE PLUMBING
J 0
(3005 1007);
DISPLAY 0.340426 (3005 1007);
PAINT GREEN (3005 1007);
DISPLAY INVISIBLE (3005 1007);
FORCEADD OFFPAGE..1
(2300 1450);
FORCEPROP 2 LAST $XR0 181 
J 0
(2018 1450);
DISPLAY 0.638298 (2018 1450);
PAINT MONO (2018 1450);
FORCEPROP 1 LAST OFFPAGE TRUE
J 0
(2625 1325);
DISPLAY 0.872340 (2625 1325);
PAINT GREEN (2625 1325);
DISPLAY INVISIBLE (2625 1325);
FORCEPROP 2 LAST PATH I192
J 0
(2350 1525);
DISPLAY 1.021277 (2350 1525);
PAINT ORANGE (2350 1525);
DISPLAY INVISIBLE (2350 1525);
FORCEPROP 1 LAST COMMENT_BODY TRUE
J 0
(2425 1350);
DISPLAY 0.872340 (2425 1350);
PAINT GREEN (2425 1350);
DISPLAY INVISIBLE (2425 1350);
FORCEPROP 2 LAST CDS_LIB mstr_standard
J 0
(2300 1450);
PAINT ORANGE (2300 1450);
DISPLAY INVISIBLE (2300 1450);
FORCEADD OFFPAGE..5
(2275 1400);
FORCEPROP 2 LAST $XR1 199 
J 0
(1900 1400);
DISPLAY 0.638298 (1900 1400);
PAINT MONO (1900 1400);
FORCEPROP 2 LAST $XR0 181 
J 0
(2020 1400);
DISPLAY 0.638298 (2020 1400);
PAINT MONO (2020 1400);
FORCEPROP 1 LAST OFFPAGE TRUE
J 0
(2600 1275);
DISPLAY 0.872340 (2600 1275);
PAINT GREEN (2600 1275);
DISPLAY INVISIBLE (2600 1275);
FORCEPROP 2 LAST PATH I193
J 0
(2325 1475);
DISPLAY 1.021277 (2325 1475);
PAINT ORANGE (2325 1475);
DISPLAY INVISIBLE (2325 1475);
FORCEPROP 1 LAST COMMENT_BODY TRUE
J 0
(2375 1325);
DISPLAY 0.872340 (2375 1325);
PAINT GREEN (2375 1325);
DISPLAY INVISIBLE (2375 1325);
FORCEPROP 2 LAST CDS_LIB mstr_standard
J 0
(2275 1400);
PAINT ORANGE (2275 1400);
DISPLAY INVISIBLE (2275 1400);
FORCEADD OFFPAGE..1
(2300 1300);
FORCEPROP 2 LAST $XR4 199 
J 0
(1658 1300);
DISPLAY 0.638298 (1658 1300);
PAINT MONO (1658 1300);
FORCEPROP 2 LAST $XR3 247 
J 0
(1658 1300);
DISPLAY 0.638298 (1658 1300);
PAINT MONO (1658 1300);
FORCEPROP 2 LAST $XR2 181 
J 0
(1778 1300);
DISPLAY 0.638298 (1778 1300);
PAINT MONO (1778 1300);
FORCEPROP 2 LAST $XR1 159 
J 0
(1898 1300);
DISPLAY 0.638298 (1898 1300);
PAINT MONO (1898 1300);
FORCEPROP 2 LAST $XR0 138 
J 0
(2018 1300);
DISPLAY 0.638298 (2018 1300);
PAINT MONO (2018 1300);
FORCEPROP 1 LAST OFFPAGE TRUE
J 0
(2625 1175);
DISPLAY 0.872340 (2625 1175);
PAINT GREEN (2625 1175);
DISPLAY INVISIBLE (2625 1175);
FORCEPROP 2 LAST PATH I194
J 0
(2350 1375);
DISPLAY 1.021277 (2350 1375);
PAINT ORANGE (2350 1375);
DISPLAY INVISIBLE (2350 1375);
FORCEPROP 1 LAST COMMENT_BODY TRUE
J 0
(2425 1200);
DISPLAY 0.872340 (2425 1200);
PAINT GREEN (2425 1200);
DISPLAY INVISIBLE (2425 1200);
FORCEPROP 2 LAST CDS_LIB mstr_standard
J 0
(2300 1300);
PAINT ORANGE (2300 1300);
DISPLAY INVISIBLE (2300 1300);
FORCEADD OFFPAGE..3
R 2
(2300 1350);
FORCEPROP 2 LAST $XR4 247 
J 0
(1660 1350);
DISPLAY 0.638298 (1660 1350);
PAINT MONO (1660 1350);
FORCEPROP 2 LAST $XR3 199 
J 0
(1660 1350);
DISPLAY 0.638298 (1660 1350);
PAINT MONO (1660 1350);
FORCEPROP 2 LAST $XR2 181 
J 0
(1780 1350);
DISPLAY 0.638298 (1780 1350);
PAINT MONO (1780 1350);
FORCEPROP 2 LAST $XR1 159 
J 0
(1900 1350);
DISPLAY 0.638298 (1900 1350);
PAINT MONO (1900 1350);
FORCEPROP 2 LAST $XR0 138 
J 0
(2020 1350);
DISPLAY 0.638298 (2020 1350);
PAINT MONO (2020 1350);
FORCEPROP 1 LAST COMMENT_BODY TRUE
J 2
(2350 1250);
DISPLAY 0.872340 (2350 1250);
PAINT GREEN (2350 1250);
DISPLAY INVISIBLE (2350 1250);
FORCEPROP 2 LAST PATH I195
J 2
(2250 1425);
DISPLAY 1.021277 (2250 1425);
PAINT ORANGE (2250 1425);
DISPLAY INVISIBLE (2250 1425);
FORCEPROP 2 LAST CDS_LIB mstr_standard
J 2
(2300 1350);
PAINT ORANGE (2300 1350);
DISPLAY INVISIBLE (2300 1350);
FORCEPROP 1 LAST OFFPAGE TRUE
J 2
(1975 1225);
DISPLAY 0.872340 (1975 1225);
PAINT GREEN (1975 1225);
DISPLAY INVISIBLE (1975 1225);
FORCEADD P3V3_STBY..1
(1725 2625);
FORCEPROP 3 LASTPIN (1725 2575) SIG_NAME P3V3_STBY\g
J 0
(1735 2585);
DISPLAY 0.659574 (1735 2585);
PAINT MONO (1735 2585);
DISPLAY INVISIBLE (1735 2585);
FORCEPROP 1 LAST VOLTAGE 3.3V
J 0
(1680 2582);
DISPLAY 0.340426 (1680 2582);
PAINT SKYBLUE (1680 2582);
DISPLAY INVISIBLE (1680 2582);
FORCEPROP 1 LAST PATH I198
J 0
(1770 2627);
DISPLAY 0.340426 (1770 2627);
PAINT GREEN (1770 2627);
DISPLAY INVISIBLE (1770 2627);
FORCEPROP 1 LAST BODY_TYPE PLUMBING
J 0
(1680 2582);
DISPLAY 0.340426 (1680 2582);
PAINT GREEN (1680 2582);
DISPLAY INVISIBLE (1680 2582);
FORCEPROP 1 LAST SIZE 1B
J 0
(1770 2647);
DISPLAY 0.340426 (1770 2647);
PAINT GREEN (1770 2647);
DISPLAY INVISIBLE (1770 2647);
FORCEPROP 2 LAST CDS_LIB mstr_symbols
J 0
(1725 2625);
PAINT ORANGE (1725 2625);
DISPLAY INVISIBLE (1725 2625);
FORCEPROP 1 LAST HDL_POWER P3V3_STBY
J 0
(1425 2500);
DISPLAY 0.872340 (1425 2500);
PAINT ORANGE (1425 2500);
DISPLAY INVISIBLE (1425 2500);
FORCEADD RES..1
(2050 2475);
FORCEPROP 1 LAST PART_NUMBER G21796-311
J 0
(2250 2425);
DISPLAY 0.617021 (2250 2425);
PAINT BLUE (2250 2425);
FORCEPROP 1 LASTPIN (2150 2475) $PN 2
J 0
(2112 2487);
DISPLAY 0.617021 (2112 2487);
PAINT ORANGE (2112 2487);
FORCEPROP 1 LAST MATERIAL CHIP
J 0
(2150 2425);
DISPLAY 0.617021 (2150 2425);
PAINT SKYBLUE (2150 2425);
FORCEPROP 1 LAST TOLERANCE 1.0%
J 0
(2025 2425);
DISPLAY 0.617021 (2025 2425);
PAINT SKYBLUE (2025 2425);
FORCEPROP 1 LAST LOCATION R7D5
J 0
(2000 2525);
DISPLAY 0.617021 (2000 2525);
PAINT AQUA (2000 2525);
FORCEPROP 1 LASTPIN (1950 2475) $PN 1
J 0
(1962 2487);
DISPLAY 0.617021 (1962 2487);
PAINT ORANGE (1962 2487);
FORCEPROP 1 LAST VALUE 2.26K
J 2
(1975 2425);
DISPLAY 0.617021 (1975 2425);
PAINT SKYBLUE (1975 2425);
FORCEPROP 1 LAST WATTAGE 1/16W
J 2
(1975 2375);
DISPLAY 0.617021 (1975 2375);
PAINT SKYBLUE (1975 2375);
FORCEPROP 1 LAST PACK_TYPE 0402
J 0
(1750 2375);
DISPLAY 0.617021 (1750 2375);
PAINT SKYBLUE (1750 2375);
FORCEPROP 2 LAST CDS_LIB mstr_discrete
J 0
(2050 2475);
PAINT ORANGE (2050 2475);
DISPLAY INVISIBLE (2050 2475);
FORCEPROP 0 LAST ROOM IO_SLOT
J 0
(2000 2625);
DISPLAY 1.021277 (2000 2625);
PAINT ORANGE (2000 2625);
DISPLAY INVISIBLE (2000 2625);
FORCEPROP 2 LAST SEC_TYPE 0402
J 0
(2000 2675);
DISPLAY 1.021277 (2000 2675);
PAINT ORANGE (2000 2675);
DISPLAY INVISIBLE (2000 2675);
FORCEPROP 2 LAST SEC 1
J 0
(2000 2675);
DISPLAY 0.680851 (2000 2675);
PAINT MONO (2000 2675);
DISPLAY INVISIBLE (2000 2675);
FORCEPROP 1 LAST PATH I199
J 0
(2000 2625);
DISPLAY 0.978723 (2000 2625);
PAINT WHITE (2000 2625);
DISPLAY INVISIBLE (2000 2625);
FORCEPROP 2 LAST CDS_LOCATION R7D5
J 0
(2000 2525);
DISPLAY 0.617021 (2000 2525);
PAINT AQUA (2000 2525);
DISPLAY INVISIBLE (2000 2525);
FORCEADD RES..1
(2050 2300);
FORCEPROP 1 LAST PART_NUMBER G21796-311
J 0
(2250 2250);
DISPLAY 0.617021 (2250 2250);
PAINT BLUE (2250 2250);
FORCEPROP 1 LASTPIN (2150 2300) $PN 2
J 0
(2112 2312);
DISPLAY 0.617021 (2112 2312);
PAINT ORANGE (2112 2312);
FORCEPROP 1 LAST MATERIAL CHIP
J 0
(2150 2250);
DISPLAY 0.617021 (2150 2250);
PAINT SKYBLUE (2150 2250);
FORCEPROP 1 LAST TOLERANCE 1.0%
J 0
(2025 2250);
DISPLAY 0.617021 (2025 2250);
PAINT SKYBLUE (2025 2250);
FORCEPROP 1 LAST LOCATION R7D9
J 0
(2000 2350);
DISPLAY 0.617021 (2000 2350);
PAINT AQUA (2000 2350);
FORCEPROP 1 LASTPIN (1950 2300) $PN 1
J 0
(1962 2312);
DISPLAY 0.617021 (1962 2312);
PAINT ORANGE (1962 2312);
FORCEPROP 1 LAST WATTAGE 1/16W
J 2
(1950 2200);
DISPLAY 0.617021 (1950 2200);
PAINT SKYBLUE (1950 2200);
FORCEPROP 1 LAST VALUE 2.26K
J 2
(1975 2250);
DISPLAY 0.617021 (1975 2250);
PAINT SKYBLUE (1975 2250);
FORCEPROP 1 LAST PACK_TYPE 0402
J 0
(1750 2200);
DISPLAY 0.617021 (1750 2200);
PAINT SKYBLUE (1750 2200);
FORCEPROP 2 LAST CDS_LIB mstr_discrete
J 0
(2050 2300);
PAINT ORANGE (2050 2300);
DISPLAY INVISIBLE (2050 2300);
FORCEPROP 0 LAST ROOM IO_SLOT
J 0
(2000 2450);
DISPLAY 1.021277 (2000 2450);
PAINT ORANGE (2000 2450);
DISPLAY INVISIBLE (2000 2450);
FORCEPROP 2 LAST SEC_TYPE 0402
J 0
(2000 2500);
DISPLAY 1.021277 (2000 2500);
PAINT ORANGE (2000 2500);
DISPLAY INVISIBLE (2000 2500);
FORCEPROP 2 LAST SEC 1
J 0
(2000 2500);
DISPLAY 0.680851 (2000 2500);
PAINT MONO (2000 2500);
DISPLAY INVISIBLE (2000 2500);
FORCEPROP 1 LAST PATH I200
J 0
(2000 2450);
DISPLAY 0.978723 (2000 2450);
PAINT WHITE (2000 2450);
DISPLAY INVISIBLE (2000 2450);
FORCEPROP 2 LAST CDS_LOCATION R7D9
J 0
(2000 2350);
DISPLAY 0.617021 (2000 2350);
PAINT AQUA (2000 2350);
DISPLAY INVISIBLE (2000 2350);
FORCEADD RES..1
(2050 2125);
FORCEPROP 1 LAST PART_NUMBER G21796-311
J 0
(2275 2075);
DISPLAY 0.617021 (2275 2075);
PAINT BLUE (2275 2075);
FORCEPROP 1 LASTPIN (2150 2125) $PN 2
J 0
(2112 2137);
DISPLAY 0.617021 (2112 2137);
PAINT ORANGE (2112 2137);
FORCEPROP 1 LAST MATERIAL CHIP
J 0
(2150 2075);
DISPLAY 0.617021 (2150 2075);
PAINT SKYBLUE (2150 2075);
FORCEPROP 1 LAST TOLERANCE 1.0%
J 0
(2025 2075);
DISPLAY 0.617021 (2025 2075);
PAINT SKYBLUE (2025 2075);
FORCEPROP 1 LAST LOCATION R3P61
J 0
(2000 2175);
DISPLAY 0.617021 (2000 2175);
PAINT AQUA (2000 2175);
FORCEPROP 1 LASTPIN (1950 2125) $PN 1
J 0
(1962 2137);
DISPLAY 0.617021 (1962 2137);
PAINT ORANGE (1962 2137);
FORCEPROP 1 LAST VALUE 2.26K
J 2
(1975 2075);
DISPLAY 0.617021 (1975 2075);
PAINT SKYBLUE (1975 2075);
FORCEPROP 1 LAST WATTAGE 1/16W
J 2
(2000 2025);
DISPLAY 0.617021 (2000 2025);
PAINT SKYBLUE (2000 2025);
FORCEPROP 1 LAST PACK_TYPE 0402
J 0
(1750 2025);
DISPLAY 0.617021 (1750 2025);
PAINT SKYBLUE (1750 2025);
FORCEPROP 2 LAST CDS_LIB mstr_discrete
J 0
(2050 2125);
PAINT ORANGE (2050 2125);
DISPLAY INVISIBLE (2050 2125);
FORCEPROP 2 LAST SEC 1
J 0
(2000 2325);
DISPLAY 0.680851 (2000 2325);
PAINT MONO (2000 2325);
DISPLAY INVISIBLE (2000 2325);
FORCEPROP 2 LAST SEC_TYPE 0402
J 0
(2000 2325);
DISPLAY 1.021277 (2000 2325);
PAINT ORANGE (2000 2325);
DISPLAY INVISIBLE (2000 2325);
FORCEPROP 1 LAST PATH I201
J 0
(2000 2275);
DISPLAY 0.978723 (2000 2275);
PAINT WHITE (2000 2275);
DISPLAY INVISIBLE (2000 2275);
FORCEPROP 0 LAST ROOM IO_SLOT
J 0
(2000 2275);
DISPLAY 1.021277 (2000 2275);
PAINT ORANGE (2000 2275);
DISPLAY INVISIBLE (2000 2275);
FORCEPROP 2 LAST CDS_LOCATION R3P61
J 0
(2000 2175);
DISPLAY 0.617021 (2000 2175);
PAINT AQUA (2000 2175);
DISPLAY INVISIBLE (2000 2175);
FORCEADD OFFPAGE..2
(2675 2125);
FORCEPROP 2 LAST $XR2 145 
J 0
(3104 2125);
DISPLAY 0.638298 (3104 2125);
PAINT MONO (3104 2125);
FORCEPROP 2 LAST $XR1 119 
J 0
(2984 2125);
DISPLAY 0.638298 (2984 2125);
PAINT MONO (2984 2125);
FORCEPROP 2 LAST $XR0 181 
J 0
(2864 2125);
DISPLAY 0.638298 (2864 2125);
PAINT MONO (2864 2125);
FORCEPROP 2 LAST PATH I202
J 0
(2850 2200);
DISPLAY 1.021277 (2850 2200);
PAINT ORANGE (2850 2200);
DISPLAY INVISIBLE (2850 2200);
FORCEPROP 2 LAST CDS_LIB mstr_standard
J 0
(2675 2125);
PAINT ORANGE (2675 2125);
DISPLAY INVISIBLE (2675 2125);
FORCEPROP 1 LAST COMMENT_BODY TRUE
J 0
(2630 2030);
DISPLAY 0.872340 (2630 2030);
PAINT GREEN (2630 2030);
DISPLAY INVISIBLE (2630 2030);
FORCEPROP 1 LAST OFFPAGE TRUE
J 0
(3000 2000);
DISPLAY 0.872340 (3000 2000);
PAINT GREEN (3000 2000);
DISPLAY INVISIBLE (3000 2000);
FORCEADD OFFPAGE..2
(2675 2300);
FORCEPROP 2 LAST $XR2 145 
J 0
(3104 2300);
DISPLAY 0.638298 (3104 2300);
PAINT MONO (3104 2300);
FORCEPROP 2 LAST $XR1 119 
J 0
(2984 2300);
DISPLAY 0.638298 (2984 2300);
PAINT MONO (2984 2300);
FORCEPROP 2 LAST $XR0 181 
J 0
(2864 2300);
DISPLAY 0.638298 (2864 2300);
PAINT MONO (2864 2300);
FORCEPROP 1 LAST OFFPAGE TRUE
J 0
(3000 2175);
DISPLAY 0.872340 (3000 2175);
PAINT GREEN (3000 2175);
DISPLAY INVISIBLE (3000 2175);
FORCEPROP 2 LAST PATH I203
J 0
(2850 2375);
DISPLAY 1.021277 (2850 2375);
PAINT ORANGE (2850 2375);
DISPLAY INVISIBLE (2850 2375);
FORCEPROP 2 LAST CDS_LIB mstr_standard
J 0
(2675 2300);
PAINT ORANGE (2675 2300);
DISPLAY INVISIBLE (2675 2300);
FORCEPROP 1 LAST COMMENT_BODY TRUE
J 0
(2630 2205);
DISPLAY 0.872340 (2630 2205);
PAINT GREEN (2630 2205);
DISPLAY INVISIBLE (2630 2205);
FORCEADD OFFPAGE..2
(2675 2475);
FORCEPROP 2 LAST $XR2 145 
J 0
(3104 2475);
DISPLAY 0.638298 (3104 2475);
PAINT MONO (3104 2475);
FORCEPROP 2 LAST $XR1 119 
J 0
(2984 2475);
DISPLAY 0.638298 (2984 2475);
PAINT MONO (2984 2475);
FORCEPROP 2 LAST $XR0 181 
J 0
(2864 2475);
DISPLAY 0.638298 (2864 2475);
PAINT MONO (2864 2475);
FORCEPROP 2 LAST PATH I204
J 0
(2850 2550);
DISPLAY 1.021277 (2850 2550);
PAINT ORANGE (2850 2550);
DISPLAY INVISIBLE (2850 2550);
FORCEPROP 1 LAST OFFPAGE TRUE
J 0
(3000 2350);
DISPLAY 0.872340 (3000 2350);
PAINT GREEN (3000 2350);
DISPLAY INVISIBLE (3000 2350);
FORCEPROP 2 LAST CDS_LIB mstr_standard
J 0
(2675 2475);
PAINT ORANGE (2675 2475);
DISPLAY INVISIBLE (2675 2475);
FORCEPROP 1 LAST COMMENT_BODY TRUE
J 0
(2630 2380);
DISPLAY 0.872340 (2630 2380);
PAINT GREEN (2630 2380);
DISPLAY INVISIBLE (2630 2380);
FORCEADD RES..1
(1050 1075);
FORCEPROP 1 LASTPIN (1150 1075) $PN 2
J 0
(1112 1087);
DISPLAY 0.617021 (1112 1087);
PAINT ORANGE (1112 1087);
FORCEPROP 1 LAST MATERIAL CHIP
J 0
(1050 925);
DISPLAY 0.617021 (1050 925);
PAINT SKYBLUE (1050 925);
FORCEPROP 1 LAST PACK_TYPE 0402
J 0
(1300 925);
DISPLAY 0.617021 (1300 925);
PAINT SKYBLUE (1300 925);
FORCEPROP 1 LAST TOLERANCE 1%
J 0
(1050 975);
DISPLAY 0.617021 (1050 975);
PAINT SKYBLUE (1050 975);
FORCEPROP 1 LAST WATTAGE 1/16W
J 2
(1025 925);
DISPLAY 0.617021 (1025 925);
PAINT SKYBLUE (1025 925);
FORCEPROP 1 LAST VALUE 33.2
J 2
(1025 975);
DISPLAY 0.617021 (1025 975);
PAINT SKYBLUE (1025 975);
FORCEPROP 1 LAST PART_NUMBER G21796-074
J 0
(850 850);
DISPLAY 0.617021 (850 850);
PAINT BLUE (850 850);
FORCEPROP 1 LAST LOCATION R8E5
J 0
(1000 1125);
DISPLAY 0.617021 (1000 1125);
PAINT AQUA (1000 1125);
FORCEPROP 1 LASTPIN (950 1075) $PN 1
J 0
(962 1087);
DISPLAY 0.617021 (962 1087);
PAINT ORANGE (962 1087);
FORCEPROP 2 LAST CDS_LIB mstr_discrete
J 0
(1050 1075);
PAINT ORANGE (1050 1075);
DISPLAY INVISIBLE (1050 1075);
FORCEPROP 1 LAST PATH I218
J 0
(1000 1225);
DISPLAY 0.978723 (1000 1225);
PAINT WHITE (1000 1225);
DISPLAY INVISIBLE (1000 1225);
FORCEPROP 2 LAST CDS_LOCATION R8E5
J 0
(1000 1125);
DISPLAY 0.617021 (1000 1125);
PAINT AQUA (1000 1125);
DISPLAY INVISIBLE (1000 1125);
FORCEPROP 2 LAST SEC 1
J 0
(1000 1275);
DISPLAY 0.680851 (1000 1275);
PAINT MONO (1000 1275);
DISPLAY INVISIBLE (1000 1275);
FORCEPROP 2 LAST SEC_TYPE 0402
J 0
(1000 1275);
DISPLAY 1.021277 (1000 1275);
PAINT ORANGE (1000 1275);
DISPLAY INVISIBLE (1000 1275);
FORCEPROP 0 LAST ROOM IO_SLOT
J 0
(1000 1225);
DISPLAY 1.021277 (1000 1225);
PAINT ORANGE (1000 1225);
DISPLAY INVISIBLE (1000 1225);
FORCEADD OFFPAGE..2
(1725 1075);
FORCEPROP 2 LAST $XR2 198 
J 0
(2154 1075);
DISPLAY 0.638298 (2154 1075);
PAINT MONO (2154 1075);
FORCEPROP 2 LAST $XR1 191 
J 0
(2034 1075);
DISPLAY 0.638298 (2034 1075);
PAINT MONO (2034 1075);
FORCEPROP 2 LAST $XR0 161 
J 0
(1914 1075);
DISPLAY 0.638298 (1914 1075);
PAINT MONO (1914 1075);
FORCEPROP 1 LAST OFFPAGE TRUE
J 0
(2050 950);
DISPLAY 0.872340 (2050 950);
PAINT GREEN (2050 950);
DISPLAY INVISIBLE (2050 950);
FORCEPROP 2 LAST PATH I221
J 0
(1900 1150);
DISPLAY 1.021277 (1900 1150);
PAINT ORANGE (1900 1150);
DISPLAY INVISIBLE (1900 1150);
FORCEPROP 2 LAST CDS_LIB mstr_standard
J 0
(1725 1075);
PAINT ORANGE (1725 1075);
DISPLAY INVISIBLE (1725 1075);
FORCEPROP 1 LAST COMMENT_BODY TRUE
J 0
(1680 980);
DISPLAY 0.872340 (1680 980);
PAINT GREEN (1680 980);
DISPLAY INVISIBLE (1680 980);
FORCEADD OFFPAGE..1
(-600 1025);
FORCEPROP 2 LAST $XR1 241 
J 0
(-972 1025);
DISPLAY 0.638298 (-972 1025);
PAINT MONO (-972 1025);
FORCEPROP 2 LAST $XR0 196 
J 0
(-852 1025);
DISPLAY 0.638298 (-852 1025);
PAINT MONO (-852 1025);
FORCEPROP 2 LAST PATH I222
J 0
(-550 1100);
DISPLAY 1.021277 (-550 1100);
PAINT ORANGE (-550 1100);
DISPLAY INVISIBLE (-550 1100);
FORCEPROP 2 LAST CDS_LIB mstr_standard
J 0
(-600 1025);
PAINT ORANGE (-600 1025);
DISPLAY INVISIBLE (-600 1025);
FORCEPROP 1 LAST OFFPAGE TRUE
J 0
(-275 900);
DISPLAY 0.872340 (-275 900);
PAINT GREEN (-275 900);
DISPLAY INVISIBLE (-275 900);
FORCEPROP 1 LAST COMMENT_BODY TRUE
J 0
(-475 925);
DISPLAY 0.872340 (-475 925);
PAINT GREEN (-475 925);
DISPLAY INVISIBLE (-475 925);
FORCEADD OFFPAGE..1
(-600 1125);
FORCEPROP 2 LAST $XR0 191 
J 0
(-852 1125);
DISPLAY 0.638298 (-852 1125);
PAINT MONO (-852 1125);
FORCEPROP 1 LAST COMMENT_BODY TRUE
J 0
(-475 1025);
DISPLAY 0.872340 (-475 1025);
PAINT GREEN (-475 1025);
DISPLAY INVISIBLE (-475 1025);
FORCEPROP 2 LAST PATH I223
J 0
(-550 1200);
DISPLAY 1.021277 (-550 1200);
PAINT ORANGE (-550 1200);
DISPLAY INVISIBLE (-550 1200);
FORCEPROP 2 LAST CDS_LIB mstr_standard
J 0
(-600 1125);
PAINT ORANGE (-600 1125);
DISPLAY INVISIBLE (-600 1125);
FORCEPROP 1 LAST OFFPAGE TRUE
J 0
(-275 1000);
DISPLAY 0.872340 (-275 1000);
PAINT GREEN (-275 1000);
DISPLAY INVISIBLE (-275 1000);
FORCEADD CAP..1
(-300 875);
FORCEPROP 1 LAST LOCATION C2R6
J 0
(-475 925);
DISPLAY 0.617021 (-475 925);
PAINT AQUA (-475 925);
FORCEPROP 1 LAST PART_NUMBER A36096-049
J 0
(-250 725);
DISPLAY 0.617021 (-250 725);
PAINT BLUE (-250 725);
FORCEPROP 1 LAST VALUE 470PF
J 0
(-250 925);
DISPLAY 0.617021 (-250 925);
PAINT SKYBLUE (-250 925);
FORCEPROP 1 LAST MATERIAL EMPTY
J 0
(-250 775);
DISPLAY 0.617021 (-250 775);
PAINT RED (-250 775);
FORCEPROP 1 LAST VOLTAGE 50V
J 0
(-250 875);
DISPLAY 0.617021 (-250 875);
PAINT SKYBLUE (-250 875);
FORCEPROP 1 LAST TOLERANCE 10%
J 0
(-250 825);
DISPLAY 0.617021 (-250 825);
PAINT SKYBLUE (-250 825);
FORCEPROP 1 LAST PACK_TYPE 0402LF
J 0
(-250 675);
DISPLAY 0.617021 (-250 675);
PAINT SKYBLUE (-250 675);
FORCEPROP 1 LASTPIN (-300 975) $PN 1
J 0
(-290 955);
DISPLAY 0.617021 (-290 955);
PAINT ORANGE (-290 955);
FORCEPROP 1 LASTPIN (-300 775) $PN 2
J 0
(-290 755);
DISPLAY 0.617021 (-290 755);
PAINT ORANGE (-290 755);
FORCEPROP 0 LAST ROOM IO_SLOT
J 0
(-250 1075);
DISPLAY 1.021277 (-250 1075);
PAINT ORANGE (-250 1075);
DISPLAY INVISIBLE (-250 1075);
FORCEPROP 2 LAST SEC_TYPE 0402LF
J 0
(-250 1075);
DISPLAY 1.021277 (-250 1075);
PAINT ORANGE (-250 1075);
DISPLAY INVISIBLE (-250 1075);
FORCEPROP 2 LAST SEC 1
J 0
(-250 1075);
DISPLAY 0.680851 (-250 1075);
PAINT MONO (-250 1075);
DISPLAY INVISIBLE (-250 1075);
FORCEPROP 1 LAST PATH I224
J 0
(-250 1025);
DISPLAY 0.978723 (-250 1025);
PAINT WHITE (-250 1025);
DISPLAY INVISIBLE (-250 1025);
FORCEPROP 2 LAST CDS_LIB mstr_discrete
J 0
(-300 875);
PAINT ORANGE (-300 875);
DISPLAY INVISIBLE (-300 875);
FORCEPROP 2 LAST CDS_LOCATION C2R6
J 0
(-475 925);
DISPLAY 0.617021 (-475 925);
PAINT AQUA (-475 925);
DISPLAY INVISIBLE (-475 925);
FORCEADD GND..1
(-300 700);
FORCEPROP 3 LASTPIN (-300 750) SIG_NAME GND\g
J 0
(-290 760);
DISPLAY 0.659574 (-290 760);
PAINT MONO (-290 760);
DISPLAY INVISIBLE (-290 760);
FORCEPROP 1 LAST PATH I225
J 0
(-225 700);
DISPLAY 0.872340 (-225 700);
PAINT AQUA (-225 700);
DISPLAY INVISIBLE (-225 700);
FORCEPROP 1 LAST SIZE 1B
J 0
(-225 650);
DISPLAY 0.872340 (-225 650);
PAINT GREEN (-225 650);
DISPLAY INVISIBLE (-225 650);
FORCEPROP 1 LAST HDL_POWER GND
J 0
(-300 850);
DISPLAY 0.872340 (-300 850);
PAINT GREEN (-300 850);
DISPLAY INVISIBLE (-300 850);
FORCEPROP 1 LAST BODY_TYPE PLUMBING
J 0
(-345 657);
DISPLAY 0.340426 (-345 657);
PAINT GREEN (-345 657);
DISPLAY INVISIBLE (-345 657);
FORCEPROP 2 LAST CDS_LIB mstr_symbols
J 0
(-300 700);
PAINT ORANGE (-300 700);
DISPLAY INVISIBLE (-300 700);
FORCEPROP 1 LAST VOLTAGE 0
J 0
(-300 700);
PAINT SKYBLUE (-300 700);
DISPLAY INVISIBLE (-300 700);
FORCEPROP 2 LAST BOM_COST NT_BASE_VRD
J 0
(-600 775);
DISPLAY 0.617021 (-600 775);
PAINT ORANGE (-600 775);
DISPLAY INVISIBLE (-600 775);
FORCEPROP 2 LAST ROOM P2V5_LAN_AUX_VR
J 0
(-600 775);
DISPLAY 0.617021 (-600 775);
PAINT ORANGE (-600 775);
DISPLAY INVISIBLE (-600 775);
FORCEADD P3V3_STBY..1
(3050 1850);
FORCEPROP 3 LASTPIN (3050 1800) SIG_NAME P3V3_STBY\g
J 0
(3060 1810);
DISPLAY 0.659574 (3060 1810);
PAINT MONO (3060 1810);
DISPLAY INVISIBLE (3060 1810);
FORCEPROP 1 LAST PATH I227
J 0
(3095 1852);
DISPLAY 0.340426 (3095 1852);
PAINT GREEN (3095 1852);
DISPLAY INVISIBLE (3095 1852);
FORCEPROP 1 LAST SIZE 1B
J 0
(3095 1872);
DISPLAY 0.340426 (3095 1872);
PAINT GREEN (3095 1872);
DISPLAY INVISIBLE (3095 1872);
FORCEPROP 1 LAST VOLTAGE 3.3V
J 0
(3005 1807);
DISPLAY 0.340426 (3005 1807);
PAINT SKYBLUE (3005 1807);
DISPLAY INVISIBLE (3005 1807);
FORCEPROP 1 LAST HDL_POWER P3V3_STBY
J 0
(2750 1725);
DISPLAY 0.872340 (2750 1725);
PAINT ORANGE (2750 1725);
DISPLAY INVISIBLE (2750 1725);
FORCEPROP 1 LAST BODY_TYPE PLUMBING
J 0
(3005 1807);
DISPLAY 0.340426 (3005 1807);
PAINT GREEN (3005 1807);
DISPLAY INVISIBLE (3005 1807);
FORCEPROP 2 LAST CDS_LIB mstr_symbols
J 0
(3050 1850);
PAINT ORANGE (3050 1850);
DISPLAY INVISIBLE (3050 1850);
FORCEADD OFFPAGE..5
(2300 1500);
FORCEPROP 2 LAST $XR3 190 
J 0
(1655 1500);
DISPLAY 0.638298 (1655 1500);
PAINT MONO (1655 1500);
FORCEPROP 2 LAST $XR2 144 
J 0
(1775 1500);
DISPLAY 0.638298 (1775 1500);
PAINT MONO (1775 1500);
FORCEPROP 2 LAST $XR1 120 
J 0
(1895 1500);
DISPLAY 0.638298 (1895 1500);
PAINT MONO (1895 1500);
FORCEPROP 2 LAST $XR0 157 
J 0
(2015 1500);
DISPLAY 0.638298 (2015 1500);
PAINT MONO (2015 1500);
FORCEPROP 1 LAST OFFPAGE TRUE
J 0
(2625 1375);
DISPLAY 0.872340 (2625 1375);
PAINT GREEN (2625 1375);
DISPLAY INVISIBLE (2625 1375);
FORCEPROP 2 LAST PATH I239
J 0
(2050 1550);
DISPLAY 1.021277 (2050 1550);
PAINT ORANGE (2050 1550);
DISPLAY INVISIBLE (2050 1550);
FORCEPROP 2 LAST CDS_LIB mstr_standard
J 0
(2300 1500);
PAINT MONO (2300 1500);
DISPLAY INVISIBLE (2300 1500);
FORCEPROP 1 LAST COMMENT_BODY TRUE
J 0
(2400 1425);
DISPLAY 0.872340 (2400 1425);
PAINT GREEN (2400 1425);
DISPLAY INVISIBLE (2400 1425);
FORCEADD OFFPAGE..5
(2300 1550);
FORCEPROP 2 LAST $XR2 120 
J 0
(1775 1550);
DISPLAY 0.638298 (1775 1550);
PAINT MONO (1775 1550);
FORCEPROP 2 LAST $XR1 157 
J 0
(1895 1550);
DISPLAY 0.638298 (1895 1550);
PAINT MONO (1895 1550);
FORCEPROP 2 LAST $XR0 147 
J 0
(2015 1550);
DISPLAY 0.638298 (2015 1550);
PAINT MONO (2015 1550);
FORCEPROP 1 LAST OFFPAGE TRUE
J 0
(2625 1425);
DISPLAY 0.872340 (2625 1425);
PAINT GREEN (2625 1425);
DISPLAY INVISIBLE (2625 1425);
FORCEPROP 2 LAST CDS_LIB mstr_standard
J 0
(2300 1550);
PAINT MONO (2300 1550);
DISPLAY INVISIBLE (2300 1550);
FORCEPROP 1 LAST COMMENT_BODY TRUE
J 0
(2400 1475);
DISPLAY 0.872340 (2400 1475);
PAINT GREEN (2400 1475);
DISPLAY INVISIBLE (2400 1475);
FORCEPROP 2 LAST PATH I241
J 0
(2025 1600);
DISPLAY 1.021277 (2025 1600);
PAINT ORANGE (2025 1600);
DISPLAY INVISIBLE (2025 1600);
FORCEADD TTL08..1
(250 1075);
FORCEPROP 2 LASTPIN (400 1075) $PN 8
J 0
(410 1085);
DISPLAY 0.617021 (410 1085);
PAINT ORANGE (410 1085);
FORCEPROP 1 LAST VALUE 74LVC08A
J 0
(150 1200);
DISPLAY 0.617021 (150 1200);
PAINT SKYBLUE (150 1200);
FORCEPROP 1 LAST LOCATION U8E1
J 0
(150 1300);
DISPLAY 0.617021 (150 1300);
PAINT AQUA (150 1300);
FORCEPROP 2 LASTPIN (100 1025) $PN 10
J 2
(90 1035);
DISPLAY 0.617021 (90 1035);
PAINT ORANGE (90 1035);
FORCEPROP 2 LASTPIN (100 1125) $PN 9
J 2
(90 1135);
DISPLAY 0.617021 (90 1135);
PAINT ORANGE (90 1135);
FORCEPROP 1 LAST MATERIAL IC
J 0
(150 1250);
DISPLAY 0.617021 (150 1250);
PAINT SKYBLUE (150 1250);
FORCEPROP 1 LAST PART_NUMBER D90404-001
J 0
(150 925);
DISPLAY 0.617021 (150 925);
PAINT BLUE (150 925);
FORCEPROP 1 LAST POWER_GROUP VCC=P3V3_STBY;GND=GND;TH=GND
J 0
(150 875);
DISPLAY 0.617021 (150 875);
PAINT ORANGE (150 875);
FORCEPROP 1 LAST PATH I243
J 0
(625 1250);
DISPLAY 0.978723 (625 1250);
PAINT BLUE (625 1250);
DISPLAY INVISIBLE (625 1250);
FORCEPROP 1 LAST PACK_TYPE QFN15
J 0
(150 1350);
DISPLAY 0.978723 (150 1350);
PAINT SKYBLUE (150 1350);
DISPLAY INVISIBLE (150 1350);
FORCEPROP 2 LAST ROOM FAST_PROCHOT
J 0
(150 1350);
DISPLAY 1.021277 (150 1350);
PAINT ORANGE (150 1350);
DISPLAY INVISIBLE (150 1350);
FORCEPROP 2 LAST CDS_LOCATION U8E1
J 0
(150 1300);
DISPLAY 0.617021 (150 1300);
PAINT AQUA (150 1300);
DISPLAY INVISIBLE (150 1300);
FORCEPROP 2 LAST SEC_TYPE QFN15
J 0
(150 1350);
DISPLAY 1.021277 (150 1350);
PAINT ORANGE (150 1350);
DISPLAY INVISIBLE (150 1350);
FORCEPROP 2 LAST BOM_COST FAST_PROCHOT
J 0
(150 1400);
DISPLAY 1.021277 (150 1400);
PAINT ORANGE (150 1400);
DISPLAY INVISIBLE (150 1400);
FORCEPROP 2 LAST SEC 2
J 0
(150 1350);
DISPLAY 0.680851 (150 1350);
PAINT MONO (150 1350);
DISPLAY INVISIBLE (150 1350);
FORCEPROP 2 LAST CDS_LIB mstr_ttl
J 0
(250 1075);
PAINT MONO (250 1075);
DISPLAY INVISIBLE (250 1075);
FORCEADD OFFPAGE..2
(1150 4500);
FORCEPROP 2 LAST $XR2 145 
J 0
(1579 4500);
DISPLAY 0.638298 (1579 4500);
PAINT MONO (1579 4500);
FORCEPROP 2 LAST $XR1 119 
J 0
(1459 4500);
DISPLAY 0.638298 (1459 4500);
PAINT MONO (1459 4500);
FORCEPROP 2 LAST $XR0 181 
J 0
(1339 4500);
DISPLAY 0.638298 (1339 4500);
PAINT MONO (1339 4500);
FORCEPROP 2 LAST PATH I244
J 0
(1325 4575);
DISPLAY 1.021277 (1325 4575);
PAINT ORANGE (1325 4575);
DISPLAY INVISIBLE (1325 4575);
FORCEPROP 1 LAST OFFPAGE TRUE
J 0
(1475 4375);
DISPLAY 0.872340 (1475 4375);
PAINT GREEN (1475 4375);
DISPLAY INVISIBLE (1475 4375);
FORCEPROP 2 LAST CDS_LIB mstr_standard
J 0
(1150 4500);
PAINT MONO (1150 4500);
DISPLAY INVISIBLE (1150 4500);
FORCEPROP 1 LAST COMMENT_BODY TRUE
J 0
(1105 4405);
DISPLAY 0.872340 (1105 4405);
PAINT GREEN (1105 4405);
DISPLAY INVISIBLE (1105 4405);
FORCEADD OFFPAGE..2
(1150 4450);
FORCEPROP 2 LAST $XR2 145 
J 0
(1579 4450);
DISPLAY 0.638298 (1579 4450);
PAINT MONO (1579 4450);
FORCEPROP 2 LAST $XR1 119 
J 0
(1459 4450);
DISPLAY 0.638298 (1459 4450);
PAINT MONO (1459 4450);
FORCEPROP 2 LAST $XR0 181 
J 0
(1339 4450);
DISPLAY 0.638298 (1339 4450);
PAINT MONO (1339 4450);
FORCEPROP 2 LAST PATH I245
J 0
(1325 4525);
DISPLAY 1.021277 (1325 4525);
PAINT ORANGE (1325 4525);
DISPLAY INVISIBLE (1325 4525);
FORCEPROP 1 LAST OFFPAGE TRUE
J 0
(1475 4325);
DISPLAY 0.872340 (1475 4325);
PAINT GREEN (1475 4325);
DISPLAY INVISIBLE (1475 4325);
FORCEPROP 2 LAST CDS_LIB mstr_standard
J 0
(1150 4450);
PAINT MONO (1150 4450);
DISPLAY INVISIBLE (1150 4450);
FORCEPROP 1 LAST COMMENT_BODY TRUE
J 0
(1105 4355);
DISPLAY 0.872340 (1105 4355);
PAINT GREEN (1105 4355);
DISPLAY INVISIBLE (1105 4355);
FORCEADD OFFPAGE..2
(1150 4400);
FORCEPROP 2 LAST $XR2 145 
J 0
(1579 4400);
DISPLAY 0.638298 (1579 4400);
PAINT MONO (1579 4400);
FORCEPROP 2 LAST $XR1 119 
J 0
(1459 4400);
DISPLAY 0.638298 (1459 4400);
PAINT MONO (1459 4400);
FORCEPROP 2 LAST $XR0 181 
J 0
(1339 4400);
DISPLAY 0.638298 (1339 4400);
PAINT MONO (1339 4400);
FORCEPROP 2 LAST PATH I246
J 0
(1325 4475);
DISPLAY 1.021277 (1325 4475);
PAINT ORANGE (1325 4475);
DISPLAY INVISIBLE (1325 4475);
FORCEPROP 1 LAST OFFPAGE TRUE
J 0
(1475 4275);
DISPLAY 0.872340 (1475 4275);
PAINT GREEN (1475 4275);
DISPLAY INVISIBLE (1475 4275);
FORCEPROP 2 LAST CDS_LIB mstr_standard
J 0
(1150 4400);
PAINT MONO (1150 4400);
DISPLAY INVISIBLE (1150 4400);
FORCEPROP 1 LAST COMMENT_BODY TRUE
J 0
(1105 4305);
DISPLAY 0.872340 (1105 4305);
PAINT GREEN (1105 4305);
DISPLAY INVISIBLE (1105 4305);
FORCEADD GND..1
(-3000 1175);
FORCEPROP 3 LASTPIN (-3000 1225) SIG_NAME GND\g
J 0
(-2990 1235);
DISPLAY 0.659574 (-2990 1235);
PAINT MONO (-2990 1235);
DISPLAY INVISIBLE (-2990 1235);
FORCEPROP 1 LAST HDL_POWER GND
J 0
(-3000 1325);
DISPLAY 0.872340 (-3000 1325);
PAINT GREEN (-3000 1325);
DISPLAY INVISIBLE (-3000 1325);
FORCEPROP 1 LAST PATH I248
J 0
(-2925 1175);
DISPLAY 0.872340 (-2925 1175);
PAINT AQUA (-2925 1175);
DISPLAY INVISIBLE (-2925 1175);
FORCEPROP 1 LAST BODY_TYPE PLUMBING
J 0
(-3045 1132);
DISPLAY 0.340426 (-3045 1132);
PAINT GREEN (-3045 1132);
DISPLAY INVISIBLE (-3045 1132);
FORCEPROP 1 LAST SIZE 1B
J 0
(-2925 1125);
DISPLAY 0.872340 (-2925 1125);
PAINT AQUA (-2925 1125);
DISPLAY INVISIBLE (-2925 1125);
FORCEPROP 2 LAST CDS_LIB mstr_symbols
J 0
(-3000 1175);
PAINT MONO (-3000 1175);
DISPLAY INVISIBLE (-3000 1175);
FORCEPROP 1 LAST VOLTAGE 0.0V
J 0
(-3045 1132);
DISPLAY 0.340426 (-3045 1132);
PAINT SKYBLUE (-3045 1132);
DISPLAY INVISIBLE (-3045 1132);
FORCEADD OFFPAGE..1
(-2975 3300);
FORCEPROP 2 LAST $XR0 161 
J 0
(-3227 3300);
DISPLAY 0.638298 (-3227 3300);
PAINT MONO (-3227 3300);
FORCEPROP 2 LAST $XR1 198 
J 0
(-3347 3300);
DISPLAY 0.638298 (-3347 3300);
PAINT MONO (-3347 3300);
FORCEPROP 2 LAST CDS_LIB mstr_standard
J 0
(-2975 3300);
PAINT ORANGE (-2975 3300);
DISPLAY INVISIBLE (-2975 3300);
FORCEPROP 1 LAST COMMENT_BODY TRUE
J 0
(-2850 3200);
DISPLAY 0.872340 (-2850 3200);
PAINT GREEN (-2850 3200);
DISPLAY INVISIBLE (-2850 3200);
FORCEPROP 2 LAST PATH I250
J 0
(-2925 3375);
DISPLAY 1.021277 (-2925 3375);
PAINT ORANGE (-2925 3375);
DISPLAY INVISIBLE (-2925 3375);
FORCEPROP 1 LAST OFFPAGE TRUE
J 0
(-2650 3175);
DISPLAY 0.872340 (-2650 3175);
PAINT GREEN (-2650 3175);
DISPLAY INVISIBLE (-2650 3175);
FORCEADD P3V3_STBY..1
(-1525 1325);
FORCEPROP 3 LASTPIN (-1525 1275) SIG_NAME P3V3_STBY\g
J 0
(-1515 1285);
DISPLAY 0.659574 (-1515 1285);
PAINT MONO (-1515 1285);
DISPLAY INVISIBLE (-1515 1285);
FORCEPROP 1 LAST PATH I251
J 0
(-1480 1327);
DISPLAY 0.340426 (-1480 1327);
PAINT GREEN (-1480 1327);
DISPLAY INVISIBLE (-1480 1327);
FORCEPROP 1 LAST SIZE 1B
J 0
(-1480 1347);
DISPLAY 0.340426 (-1480 1347);
PAINT GREEN (-1480 1347);
DISPLAY INVISIBLE (-1480 1347);
FORCEPROP 2 LAST CDS_LIB mstr_symbols
J 0
(-1525 1325);
PAINT ORANGE (-1525 1325);
DISPLAY INVISIBLE (-1525 1325);
FORCEPROP 1 LAST BODY_TYPE PLUMBING
J 0
(-1570 1282);
DISPLAY 0.340426 (-1570 1282);
PAINT GREEN (-1570 1282);
DISPLAY INVISIBLE (-1570 1282);
FORCEPROP 1 LAST HDL_POWER P3V3_STBY
J 0
(-1825 1200);
DISPLAY 0.872340 (-1825 1200);
PAINT ORANGE (-1825 1200);
DISPLAY INVISIBLE (-1825 1200);
FORCEPROP 1 LAST VOLTAGE 3.3V
J 0
(-1570 1282);
DISPLAY 0.340426 (-1570 1282);
PAINT SKYBLUE (-1570 1282);
DISPLAY INVISIBLE (-1570 1282);
FORCEADD GND..1
(-1525 725);
FORCEPROP 3 LASTPIN (-1525 775) SIG_NAME GND\g
J 0
(-1515 785);
DISPLAY 0.659574 (-1515 785);
PAINT MONO (-1515 785);
DISPLAY INVISIBLE (-1515 785);
FORCEPROP 1 LAST HDL_POWER GND
J 0
(-1525 875);
DISPLAY 0.872340 (-1525 875);
PAINT GREEN (-1525 875);
DISPLAY INVISIBLE (-1525 875);
FORCEPROP 1 LAST SIZE 1B
J 0
(-1450 675);
DISPLAY 0.872340 (-1450 675);
PAINT AQUA (-1450 675);
DISPLAY INVISIBLE (-1450 675);
FORCEPROP 1 LAST PATH I252
J 0
(-1450 725);
DISPLAY 0.872340 (-1450 725);
PAINT AQUA (-1450 725);
DISPLAY INVISIBLE (-1450 725);
FORCEPROP 2 LAST CDS_LIB mstr_symbols
J 0
(-1525 725);
PAINT ORANGE (-1525 725);
DISPLAY INVISIBLE (-1525 725);
FORCEPROP 1 LAST BODY_TYPE PLUMBING
J 0
(-1570 682);
DISPLAY 0.340426 (-1570 682);
PAINT GREEN (-1570 682);
DISPLAY INVISIBLE (-1570 682);
FORCEPROP 1 LAST VOLTAGE 0.0V
J 0
(-1570 682);
DISPLAY 0.340426 (-1570 682);
PAINT SKYBLUE (-1570 682);
DISPLAY INVISIBLE (-1570 682);
FORCEADD CAP_A..1
(-1525 1025);
FORCEPROP 1 LAST LOCATION C8E1
J 0
(-1475 1125);
DISPLAY 0.617021 (-1475 1125);
PAINT AQUA (-1475 1125);
FORCEPROP 1 LAST VALUE 0.1UF
J 0
(-1475 1075);
DISPLAY 0.617021 (-1475 1075);
PAINT SKYBLUE (-1475 1075);
FORCEPROP 1 LAST VOLTAGE 16V
J 0
(-1475 1025);
DISPLAY 0.617021 (-1475 1025);
PAINT SKYBLUE (-1475 1025);
FORCEPROP 1 LASTPIN (-1525 1125) $PN 1
J 0
(-1515 1105);
DISPLAY 0.617021 (-1515 1105);
PAINT ORANGE (-1515 1105);
FORCEPROP 1 LAST PART_NUMBER A36096-030
J 0
(-1475 875);
DISPLAY 0.617021 (-1475 875);
PAINT BLUE (-1475 875);
FORCEPROP 1 LASTPIN (-1525 925) $PN 2
J 0
(-1515 905);
DISPLAY 0.617021 (-1515 905);
PAINT ORANGE (-1515 905);
FORCEPROP 1 LAST MATERIAL X7R
J 0
(-1475 925);
DISPLAY 0.617021 (-1475 925);
PAINT SKYBLUE (-1475 925);
FORCEPROP 1 LAST PACK_TYPE 0402V
J 0
(-1475 825);
DISPLAY 0.617021 (-1475 825);
PAINT SKYBLUE (-1475 825);
FORCEPROP 1 LAST TOLERANCE 10%
J 0
(-1475 975);
DISPLAY 0.617021 (-1475 975);
PAINT SKYBLUE (-1475 975);
FORCEPROP 2 LAST ROOM IO_SLOT
J 0
(-1475 1175);
DISPLAY 1.021277 (-1475 1175);
PAINT ORANGE (-1475 1175);
DISPLAY INVISIBLE (-1475 1175);
FORCEPROP 2 LAST SEC 1
J 0
(-1475 1175);
DISPLAY 0.680851 (-1475 1175);
PAINT MONO (-1475 1175);
DISPLAY INVISIBLE (-1475 1175);
FORCEPROP 2 LAST SEC_TYPE 0402V
J 0
(-1475 1225);
DISPLAY 1.021277 (-1475 1225);
PAINT ORANGE (-1475 1225);
DISPLAY INVISIBLE (-1475 1225);
FORCEPROP 2 LAST CDS_SEC 1
J 0
(-1475 1175);
PAINT ORANGE (-1475 1175);
DISPLAY INVISIBLE (-1475 1175);
FORCEPROP 2 LAST BOM_COST IO_SLOT
J 0
(-1475 1225);
DISPLAY 1.021277 (-1475 1225);
PAINT ORANGE (-1475 1225);
DISPLAY INVISIBLE (-1475 1225);
FORCEPROP 1 LAST PATH I253
J 0
(-1475 1175);
DISPLAY 0.978723 (-1475 1175);
PAINT WHITE (-1475 1175);
DISPLAY INVISIBLE (-1475 1175);
FORCEPROP 2 LAST CDS_LIB dev_discrete
J 0
(-1525 1025);
PAINT ORANGE (-1525 1025);
DISPLAY INVISIBLE (-1525 1025);
FORCEPROP 2 LAST CDS_LOCATION C8E1
J 0
(-1475 1125);
DISPLAY 0.617021 (-1475 1125);
PAINT AQUA (-1475 1125);
DISPLAY INVISIBLE (-1475 1125);
FORCEADD RES..1
(-2125 3200);
FORCEPROP 1 LAST PART_NUMBER G21497-005
J 0
(-2025 3200);
DISPLAY 0.617021 (-2025 3200);
PAINT BLUE (-2025 3200);
FORCEPROP 1 LAST TOLERANCE 5%
J 0
(-2075 3150);
DISPLAY 0.617021 (-2075 3150);
PAINT SKYBLUE (-2075 3150);
FORCEPROP 1 LAST LOCATION R9R9
J 0
(-2150 3250);
DISPLAY 0.617021 (-2150 3250);
PAINT AQUA (-2150 3250);
FORCEPROP 1 LAST PACK_TYPE 0402
J 0
(-1875 3150);
DISPLAY 0.617021 (-1875 3150);
PAINT SKYBLUE (-1875 3150);
FORCEPROP 1 LAST MATERIAL CHIP
J 0
(-2000 3150);
DISPLAY 0.617021 (-2000 3150);
PAINT SKYBLUE (-2000 3150);
FORCEPROP 1 LASTPIN (-2025 3200) $PN 2
J 0
(-2063 3212);
DISPLAY 0.617021 (-2063 3212);
PAINT ORANGE (-2063 3212);
FORCEPROP 1 LAST VALUE 0.0
J 2
(-2150 3150);
DISPLAY 0.617021 (-2150 3150);
PAINT SKYBLUE (-2150 3150);
FORCEPROP 1 LASTPIN (-2225 3200) $PN 1
J 0
(-2213 3212);
DISPLAY 0.617021 (-2213 3212);
PAINT ORANGE (-2213 3212);
FORCEPROP 1 LAST WATTAGE 1/16W
J 2
(-2250 3150);
DISPLAY 0.617021 (-2250 3150);
PAINT SKYBLUE (-2250 3150);
FORCEPROP 1 LAST PATH I254
J 0
(-2175 3350);
DISPLAY 0.978723 (-2175 3350);
PAINT WHITE (-2175 3350);
DISPLAY INVISIBLE (-2175 3350);
FORCEPROP 2 LAST SEC 1
J 0
(-2175 3400);
DISPLAY 0.680851 (-2175 3400);
PAINT MONO (-2175 3400);
DISPLAY INVISIBLE (-2175 3400);
FORCEPROP 2 LAST SEC_TYPE 0402
J 0
(-2175 3400);
DISPLAY 1.021277 (-2175 3400);
PAINT ORANGE (-2175 3400);
DISPLAY INVISIBLE (-2175 3400);
FORCEPROP 2 LAST CDS_LOCATION R9R9
J 0
(-2150 3250);
DISPLAY 0.617021 (-2150 3250);
PAINT AQUA (-2150 3250);
DISPLAY INVISIBLE (-2150 3250);
FORCEPROP 2 LAST CDS_LIB mstr_discrete
J 0
(-2125 3200);
PAINT ORANGE (-2125 3200);
DISPLAY INVISIBLE (-2125 3200);
FORCEADD RES..1
(-2825 3150);
FORCEPROP 1 LAST LOCATION R9R12
J 0
(-2875 3200);
DISPLAY 0.617021 (-2875 3200);
PAINT AQUA (-2875 3200);
FORCEPROP 1 LAST PART_NUMBER G21497-005
J 0
(-2725 3150);
DISPLAY 0.617021 (-2725 3150);
PAINT BLUE (-2725 3150);
FORCEPROP 1 LAST WATTAGE 1/16W
J 2
(-2950 3100);
DISPLAY 0.617021 (-2950 3100);
PAINT SKYBLUE (-2950 3100);
FORCEPROP 1 LAST VALUE 0.0
J 2
(-2850 3100);
DISPLAY 0.617021 (-2850 3100);
PAINT SKYBLUE (-2850 3100);
FORCEPROP 1 LASTPIN (-2725 3150) $PN 2
J 0
(-2763 3162);
DISPLAY 0.617021 (-2763 3162);
PAINT ORANGE (-2763 3162);
FORCEPROP 1 LAST TOLERANCE 5%
J 0
(-2775 3100);
DISPLAY 0.617021 (-2775 3100);
PAINT SKYBLUE (-2775 3100);
FORCEPROP 1 LASTPIN (-2925 3150) $PN 1
J 0
(-2913 3162);
DISPLAY 0.617021 (-2913 3162);
PAINT ORANGE (-2913 3162);
FORCEPROP 1 LAST MATERIAL CHIP
J 0
(-2700 3100);
DISPLAY 0.617021 (-2700 3100);
PAINT SKYBLUE (-2700 3100);
FORCEPROP 1 LAST PACK_TYPE 0402
J 0
(-2575 3100);
DISPLAY 0.617021 (-2575 3100);
PAINT SKYBLUE (-2575 3100);
FORCEPROP 2 LAST SEC_TYPE 0402
J 0
(-2875 3350);
DISPLAY 1.021277 (-2875 3350);
PAINT ORANGE (-2875 3350);
DISPLAY INVISIBLE (-2875 3350);
FORCEPROP 2 LAST SEC 1
J 0
(-2875 3350);
DISPLAY 0.680851 (-2875 3350);
PAINT MONO (-2875 3350);
DISPLAY INVISIBLE (-2875 3350);
FORCEPROP 1 LAST PATH I255
J 0
(-2875 3300);
DISPLAY 0.978723 (-2875 3300);
PAINT WHITE (-2875 3300);
DISPLAY INVISIBLE (-2875 3300);
FORCEPROP 2 LAST CDS_LOCATION R9R12
J 0
(-2875 3200);
DISPLAY 0.617021 (-2875 3200);
PAINT AQUA (-2875 3200);
DISPLAY INVISIBLE (-2875 3200);
FORCEPROP 2 LAST CDS_LIB mstr_discrete
J 0
(-2825 3150);
PAINT ORANGE (-2825 3150);
DISPLAY INVISIBLE (-2825 3150);
FORCEADD RES..1
(-2125 3100);
FORCEPROP 1 LAST TOLERANCE 5%
J 0
(-2075 3050);
DISPLAY 0.617021 (-2075 3050);
PAINT SKYBLUE (-2075 3050);
FORCEPROP 1 LAST PACK_TYPE 0402
J 0
(-1875 3050);
DISPLAY 0.617021 (-1875 3050);
PAINT SKYBLUE (-1875 3050);
FORCEPROP 1 LAST PART_NUMBER G21497-005
J 0
(-2025 3100);
DISPLAY 0.617021 (-2025 3100);
PAINT BLUE (-2025 3100);
FORCEPROP 1 LAST LOCATION R9R10
J 0
(-2175 3125);
DISPLAY 0.617021 (-2175 3125);
PAINT AQUA (-2175 3125);
FORCEPROP 1 LASTPIN (-2025 3100) $PN 2
J 0
(-2063 3112);
DISPLAY 0.617021 (-2063 3112);
PAINT ORANGE (-2063 3112);
FORCEPROP 1 LASTPIN (-2225 3100) $PN 1
J 0
(-2213 3112);
DISPLAY 0.617021 (-2213 3112);
PAINT ORANGE (-2213 3112);
FORCEPROP 1 LAST VALUE 0.0
J 2
(-2150 3050);
DISPLAY 0.617021 (-2150 3050);
PAINT SKYBLUE (-2150 3050);
FORCEPROP 1 LAST WATTAGE 1/16W
J 2
(-2250 3050);
DISPLAY 0.617021 (-2250 3050);
PAINT SKYBLUE (-2250 3050);
FORCEPROP 1 LAST MATERIAL CHIP
J 0
(-2000 3050);
DISPLAY 0.617021 (-2000 3050);
PAINT SKYBLUE (-2000 3050);
FORCEPROP 2 LAST SEC 1
J 0
(-2175 3300);
DISPLAY 0.680851 (-2175 3300);
PAINT MONO (-2175 3300);
DISPLAY INVISIBLE (-2175 3300);
FORCEPROP 2 LAST SEC_TYPE 0402
J 0
(-2175 3300);
DISPLAY 1.021277 (-2175 3300);
PAINT ORANGE (-2175 3300);
DISPLAY INVISIBLE (-2175 3300);
FORCEPROP 1 LAST PATH I256
J 0
(-2175 3250);
DISPLAY 0.978723 (-2175 3250);
PAINT WHITE (-2175 3250);
DISPLAY INVISIBLE (-2175 3250);
FORCEPROP 2 LAST CDS_LOCATION R9R10
J 0
(-2175 3125);
DISPLAY 0.617021 (-2175 3125);
PAINT AQUA (-2175 3125);
DISPLAY INVISIBLE (-2175 3125);
FORCEPROP 2 LAST CDS_LIB mstr_discrete
J 0
(-2125 3100);
PAINT ORANGE (-2125 3100);
DISPLAY INVISIBLE (-2125 3100);
FORCEADD OFFPAGE..5
(-3525 3150);
FORCEPROP 2 LAST $XR2 147 
J 0
(-4020 3150);
DISPLAY 0.638298 (-4020 3150);
PAINT MONO (-4020 3150);
FORCEPROP 2 LAST $XR1 120 
J 0
(-3900 3150);
DISPLAY 0.638298 (-3900 3150);
PAINT MONO (-3900 3150);
FORCEPROP 2 LAST $XR0 161 
J 0
(-3780 3150);
DISPLAY 0.638298 (-3780 3150);
PAINT MONO (-3780 3150);
FORCEPROP 1 LAST COMMENT_BODY TRUE
J 0
(-3425 3075);
DISPLAY 0.872340 (-3425 3075);
PAINT GREEN (-3425 3075);
DISPLAY INVISIBLE (-3425 3075);
FORCEPROP 2 LAST PATH I257
J 0
(-3475 3225);
DISPLAY 1.021277 (-3475 3225);
PAINT ORANGE (-3475 3225);
DISPLAY INVISIBLE (-3475 3225);
FORCEPROP 2 LAST CDS_LIB mstr_standard
J 0
(-3525 3150);
PAINT ORANGE (-3525 3150);
DISPLAY INVISIBLE (-3525 3150);
FORCEPROP 1 LAST OFFPAGE TRUE
J 0
(-3200 3025);
DISPLAY 0.872340 (-3200 3025);
PAINT GREEN (-3200 3025);
DISPLAY INVISIBLE (-3200 3025);
FORCEADD OFFPAGE..5
(-3525 3200);
FORCEPROP 2 LAST $XR0 161 
J 0
(-3780 3200);
DISPLAY 0.638298 (-3780 3200);
PAINT MONO (-3780 3200);
FORCEPROP 2 LAST $XR2 147 
J 0
(-4020 3200);
DISPLAY 0.638298 (-4020 3200);
PAINT MONO (-4020 3200);
FORCEPROP 2 LAST $XR1 120 
J 0
(-3900 3200);
DISPLAY 0.638298 (-3900 3200);
PAINT MONO (-3900 3200);
FORCEPROP 1 LAST OFFPAGE TRUE
J 0
(-3200 3075);
DISPLAY 0.872340 (-3200 3075);
PAINT GREEN (-3200 3075);
DISPLAY INVISIBLE (-3200 3075);
FORCEPROP 1 LAST COMMENT_BODY TRUE
J 0
(-3425 3125);
DISPLAY 0.872340 (-3425 3125);
PAINT GREEN (-3425 3125);
DISPLAY INVISIBLE (-3425 3125);
FORCEPROP 2 LAST PATH I258
J 0
(-3475 3275);
DISPLAY 1.021277 (-3475 3275);
PAINT ORANGE (-3475 3275);
DISPLAY INVISIBLE (-3475 3275);
FORCEPROP 2 LAST CDS_LIB mstr_standard
J 0
(-3525 3200);
PAINT ORANGE (-3525 3200);
DISPLAY INVISIBLE (-3525 3200);
FORCEADD OFFPAGE..5
(-3525 3100);
FORCEPROP 2 LAST $XR2 147 
J 0
(-4020 3100);
DISPLAY 0.638298 (-4020 3100);
PAINT MONO (-4020 3100);
FORCEPROP 2 LAST $XR1 120 
J 0
(-3900 3100);
DISPLAY 0.638298 (-3900 3100);
PAINT MONO (-3900 3100);
FORCEPROP 2 LAST $XR0 161 
J 0
(-3780 3100);
DISPLAY 0.638298 (-3780 3100);
PAINT MONO (-3780 3100);
FORCEPROP 2 LAST PATH I259
J 0
(-3475 3175);
DISPLAY 1.021277 (-3475 3175);
PAINT ORANGE (-3475 3175);
DISPLAY INVISIBLE (-3475 3175);
FORCEPROP 2 LAST CDS_LIB mstr_standard
J 0
(-3525 3100);
PAINT ORANGE (-3525 3100);
DISPLAY INVISIBLE (-3525 3100);
FORCEPROP 1 LAST OFFPAGE TRUE
J 0
(-3200 2975);
DISPLAY 0.872340 (-3200 2975);
PAINT GREEN (-3200 2975);
DISPLAY INVISIBLE (-3200 2975);
FORCEPROP 1 LAST COMMENT_BODY TRUE
J 0
(-3425 3025);
DISPLAY 0.872340 (-3425 3025);
PAINT GREEN (-3425 3025);
DISPLAY INVISIBLE (-3425 3025);
FORCEADD RES..1
(-2100 2950);
FORCEPROP 1 LAST WATTAGE 1/16W
J 2
(-2225 2900);
DISPLAY 0.617021 (-2225 2900);
PAINT SKYBLUE (-2225 2900);
FORCEPROP 1 LASTPIN (-2200 2950) $PN 1
J 0
(-2188 2962);
DISPLAY 0.617021 (-2188 2962);
PAINT ORANGE (-2188 2962);
FORCEPROP 1 LASTPIN (-2000 2950) $PN 2
J 0
(-2038 2962);
DISPLAY 0.617021 (-2038 2962);
PAINT ORANGE (-2038 2962);
FORCEPROP 1 LAST VALUE 0.0
J 2
(-2125 2900);
DISPLAY 0.617021 (-2125 2900);
PAINT SKYBLUE (-2125 2900);
FORCEPROP 1 LAST LOCATION R9T1
J 0
(-2150 2975);
DISPLAY 0.617021 (-2150 2975);
PAINT AQUA (-2150 2975);
FORCEPROP 1 LAST TOLERANCE 5%
J 0
(-2050 2900);
DISPLAY 0.617021 (-2050 2900);
PAINT SKYBLUE (-2050 2900);
FORCEPROP 1 LAST MATERIAL CHIP
J 0
(-1975 2900);
DISPLAY 0.617021 (-1975 2900);
PAINT SKYBLUE (-1975 2900);
FORCEPROP 1 LAST PACK_TYPE 0402
J 0
(-1850 2900);
DISPLAY 0.617021 (-1850 2900);
PAINT SKYBLUE (-1850 2900);
FORCEPROP 1 LAST PART_NUMBER G21497-005
J 0
(-1975 2950);
DISPLAY 0.617021 (-1975 2950);
PAINT BLUE (-1975 2950);
FORCEPROP 2 LAST CDS_LOCATION R9T1
J 0
(-2150 2975);
DISPLAY 0.617021 (-2150 2975);
PAINT AQUA (-2150 2975);
DISPLAY INVISIBLE (-2150 2975);
FORCEPROP 2 LAST CDS_LIB mstr_discrete
J 0
(-2100 2950);
PAINT ORANGE (-2100 2950);
DISPLAY INVISIBLE (-2100 2950);
FORCEPROP 2 LAST SEC_TYPE 0402
J 0
(-2150 3150);
DISPLAY 1.021277 (-2150 3150);
PAINT ORANGE (-2150 3150);
DISPLAY INVISIBLE (-2150 3150);
FORCEPROP 2 LAST SEC 1
J 0
(-2150 3150);
DISPLAY 0.680851 (-2150 3150);
PAINT MONO (-2150 3150);
DISPLAY INVISIBLE (-2150 3150);
FORCEPROP 1 LAST PATH I261
J 0
(-2150 3100);
DISPLAY 0.978723 (-2150 3100);
PAINT WHITE (-2150 3100);
DISPLAY INVISIBLE (-2150 3100);
FORCEADD OFFPAGE..1
(-3500 2950);
FORCEPROP 2 LAST $XR0 161 
J 0
(-3752 2950);
DISPLAY 0.638298 (-3752 2950);
PAINT MONO (-3752 2950);
FORCEPROP 1 LAST OFFPAGE TRUE
J 0
(-3175 2825);
DISPLAY 0.872340 (-3175 2825);
PAINT GREEN (-3175 2825);
DISPLAY INVISIBLE (-3175 2825);
FORCEPROP 2 LAST PATH I262
J 0
(-3450 3025);
DISPLAY 1.021277 (-3450 3025);
PAINT ORANGE (-3450 3025);
DISPLAY INVISIBLE (-3450 3025);
FORCEPROP 1 LAST COMMENT_BODY TRUE
J 0
(-3375 2850);
DISPLAY 0.872340 (-3375 2850);
PAINT GREEN (-3375 2850);
DISPLAY INVISIBLE (-3375 2850);
FORCEPROP 2 LAST CDS_LIB mstr_standard
J 0
(-3500 2950);
PAINT ORANGE (-3500 2950);
DISPLAY INVISIBLE (-3500 2950);
FORCEADD OFFPAGE..1
(-3475 2425);
FORCEPROP 2 LAST $XR0 182 
J 0
(-3757 2425);
DISPLAY 0.638298 (-3757 2425);
PAINT MONO (-3757 2425);
FORCEPROP 1 LAST OFFPAGE TRUE
J 0
(-3150 2300);
DISPLAY 0.872340 (-3150 2300);
PAINT GREEN (-3150 2300);
DISPLAY INVISIBLE (-3150 2300);
FORCEPROP 2 LAST PATH I263
J 0
(-3425 2500);
DISPLAY 1.021277 (-3425 2500);
PAINT ORANGE (-3425 2500);
DISPLAY INVISIBLE (-3425 2500);
FORCEPROP 1 LAST COMMENT_BODY TRUE
J 0
(-3350 2325);
DISPLAY 0.872340 (-3350 2325);
PAINT GREEN (-3350 2325);
DISPLAY INVISIBLE (-3350 2325);
FORCEPROP 2 LAST CDS_LIB mstr_standard
J 0
(-3475 2425);
PAINT ORANGE (-3475 2425);
DISPLAY INVISIBLE (-3475 2425);
FORCEADD OFFPAGE..1
(-3475 2525);
FORCEPROP 2 LAST $XR0 182 
J 0
(-3727 2525);
DISPLAY 0.638298 (-3727 2525);
PAINT MONO (-3727 2525);
FORCEPROP 2 LAST PATH I264
J 0
(-3425 2600);
DISPLAY 1.021277 (-3425 2600);
PAINT ORANGE (-3425 2600);
DISPLAY INVISIBLE (-3425 2600);
FORCEPROP 2 LAST CDS_LIB mstr_standard
J 0
(-3475 2525);
PAINT ORANGE (-3475 2525);
DISPLAY INVISIBLE (-3475 2525);
FORCEPROP 1 LAST OFFPAGE TRUE
J 0
(-3150 2400);
DISPLAY 0.872340 (-3150 2400);
PAINT GREEN (-3150 2400);
DISPLAY INVISIBLE (-3150 2400);
FORCEPROP 1 LAST COMMENT_BODY TRUE
J 0
(-3350 2425);
DISPLAY 0.872340 (-3350 2425);
PAINT GREEN (-3350 2425);
DISPLAY INVISIBLE (-3350 2425);
FORCEADD OFFPAGE..1
(-3475 2575);
FORCEPROP 2 LAST $XR0 182 
J 0
(-3757 2575);
DISPLAY 0.638298 (-3757 2575);
PAINT MONO (-3757 2575);
FORCEPROP 2 LAST PATH I265
J 0
(-3425 2650);
DISPLAY 1.021277 (-3425 2650);
PAINT ORANGE (-3425 2650);
DISPLAY INVISIBLE (-3425 2650);
FORCEPROP 2 LAST CDS_LIB mstr_standard
J 0
(-3475 2575);
PAINT ORANGE (-3475 2575);
DISPLAY INVISIBLE (-3475 2575);
FORCEPROP 1 LAST OFFPAGE TRUE
J 0
(-3150 2450);
DISPLAY 0.872340 (-3150 2450);
PAINT GREEN (-3150 2450);
DISPLAY INVISIBLE (-3150 2450);
FORCEPROP 1 LAST COMMENT_BODY TRUE
J 0
(-3350 2475);
DISPLAY 0.872340 (-3350 2475);
PAINT GREEN (-3350 2475);
DISPLAY INVISIBLE (-3350 2475);
FORCEADD OFFPAGE..6
(-3475 2625);
FORCEPROP 2 LAST $XR0 182 
J 0
(-3785 2625);
DISPLAY 0.638298 (-3785 2625);
PAINT MONO (-3785 2625);
FORCEPROP 2 LAST PATH I266
J 0
(-3425 2700);
DISPLAY 1.021277 (-3425 2700);
PAINT ORANGE (-3425 2700);
DISPLAY INVISIBLE (-3425 2700);
FORCEPROP 2 LAST CDS_LIB mstr_standard
J 0
(-3475 2625);
PAINT ORANGE (-3475 2625);
DISPLAY INVISIBLE (-3475 2625);
FORCEPROP 1 LAST COMMENT_BODY TRUE
J 0
(-3375 2550);
DISPLAY 0.872340 (-3375 2550);
PAINT GREEN (-3375 2550);
DISPLAY INVISIBLE (-3375 2550);
FORCEPROP 1 LAST OFFPAGE TRUE
J 0
(-3150 2500);
DISPLAY 0.872340 (-3150 2500);
PAINT GREEN (-3150 2500);
DISPLAY INVISIBLE (-3150 2500);
FORCEADD OFFPAGE..5
(-3475 2475);
FORCEPROP 2 LAST $XR0 182 
J 0
(-3760 2475);
DISPLAY 0.638298 (-3760 2475);
PAINT MONO (-3760 2475);
FORCEPROP 2 LAST PATH I267
J 0
(-3425 2550);
DISPLAY 1.021277 (-3425 2550);
PAINT ORANGE (-3425 2550);
DISPLAY INVISIBLE (-3425 2550);
FORCEPROP 1 LAST OFFPAGE TRUE
J 0
(-3150 2350);
DISPLAY 0.872340 (-3150 2350);
PAINT GREEN (-3150 2350);
DISPLAY INVISIBLE (-3150 2350);
FORCEPROP 1 LAST COMMENT_BODY TRUE
J 0
(-3375 2400);
DISPLAY 0.872340 (-3375 2400);
PAINT GREEN (-3375 2400);
DISPLAY INVISIBLE (-3375 2400);
FORCEPROP 2 LAST CDS_LIB mstr_standard
J 0
(-3475 2475);
PAINT ORANGE (-3475 2475);
DISPLAY INVISIBLE (-3475 2475);
FORCEADD RES..1
(-2825 3050);
FORCEPROP 1 LASTPIN (-2925 3050) $PN 1
J 0
(-2913 3062);
DISPLAY 0.617021 (-2913 3062);
PAINT ORANGE (-2913 3062);
FORCEPROP 1 LASTPIN (-2725 3050) $PN 2
J 0
(-2763 3062);
DISPLAY 0.617021 (-2763 3062);
PAINT ORANGE (-2763 3062);
FORCEPROP 1 LAST LOCATION R1F8
J 0
(-3075 3050);
DISPLAY 0.617021 (-3075 3050);
PAINT AQUA (-3075 3050);
FORCEPROP 1 LAST PART_NUMBER G21497-005
J 0
(-2725 3050);
DISPLAY 0.617021 (-2725 3050);
PAINT BLUE (-2725 3050);
FORCEPROP 1 LAST VALUE 0.0
J 2
(-2400 3050);
DISPLAY 0.617021 (-2400 3050);
PAINT SKYBLUE (-2400 3050);
FORCEPROP 1 LAST PATH I268
J 0
(-2875 3200);
DISPLAY 0.978723 (-2875 3200);
PAINT WHITE (-2875 3200);
DISPLAY INVISIBLE (-2875 3200);
FORCEPROP 2 LAST SEC 1
J 0
(-2875 3250);
DISPLAY 0.680851 (-2875 3250);
PAINT MONO (-2875 3250);
DISPLAY INVISIBLE (-2875 3250);
FORCEPROP 2 LAST SEC_TYPE 0402
J 0
(-2875 3250);
DISPLAY 1.021277 (-2875 3250);
PAINT ORANGE (-2875 3250);
DISPLAY INVISIBLE (-2875 3250);
FORCEPROP 2 LAST CDS_LIB mstr_discrete
J 0
(-2825 3050);
PAINT ORANGE (-2825 3050);
DISPLAY INVISIBLE (-2825 3050);
FORCEPROP 1 LAST PACK_TYPE 0402
J 0
(-2575 3000);
DISPLAY 0.617021 (-2575 3000);
PAINT SKYBLUE (-2575 3000);
DISPLAY INVISIBLE (-2575 3000);
FORCEPROP 1 LAST MATERIAL CHIP
J 0
(-2700 3000);
DISPLAY 0.617021 (-2700 3000);
PAINT SKYBLUE (-2700 3000);
DISPLAY INVISIBLE (-2700 3000);
FORCEPROP 1 LAST TOLERANCE 5%
J 0
(-2775 3000);
DISPLAY 0.617021 (-2775 3000);
PAINT SKYBLUE (-2775 3000);
DISPLAY INVISIBLE (-2775 3000);
FORCEPROP 1 LAST WATTAGE 1/16W
J 2
(-2950 3000);
DISPLAY 0.617021 (-2950 3000);
PAINT SKYBLUE (-2950 3000);
DISPLAY INVISIBLE (-2950 3000);
FORCEPROP 2 LAST CDS_LOCATION R1F8
J 0
(-3075 3050);
DISPLAY 0.617021 (-3075 3050);
PAINT AQUA (-3075 3050);
DISPLAY INVISIBLE (-3075 3050);
FORCEADD OFFPAGE..5
(-3525 3050);
FORCEPROP 2 LAST $XR2 147 
J 0
(-4020 3050);
DISPLAY 0.638298 (-4020 3050);
PAINT MONO (-4020 3050);
FORCEPROP 2 LAST $XR1 120 
J 0
(-3900 3050);
DISPLAY 0.638298 (-3900 3050);
PAINT MONO (-3900 3050);
FORCEPROP 2 LAST $XR0 161 
J 0
(-3780 3050);
DISPLAY 0.638298 (-3780 3050);
PAINT MONO (-3780 3050);
FORCEPROP 2 LAST PATH I269
J 0
(-4075 3125);
DISPLAY 1.021277 (-4075 3125);
PAINT ORANGE (-4075 3125);
DISPLAY INVISIBLE (-4075 3125);
FORCEPROP 2 LAST CDS_LIB mstr_standard
J 0
(-3525 3050);
PAINT ORANGE (-3525 3050);
DISPLAY INVISIBLE (-3525 3050);
FORCEPROP 1 LAST OFFPAGE TRUE
J 0
(-3200 2925);
DISPLAY 0.872340 (-3200 2925);
PAINT GREEN (-3200 2925);
DISPLAY INVISIBLE (-3200 2925);
FORCEPROP 1 LAST COMMENT_BODY TRUE
J 0
(-3425 2975);
DISPLAY 0.872340 (-3425 2975);
PAINT GREEN (-3425 2975);
DISPLAY INVISIBLE (-3425 2975);
FORCEADD OFFPAGE..1
(-3700 3400);
FORCEPROP 2 LAST $XR2 155 
J 0
(-4072 3400);
DISPLAY 0.638298 (-4072 3400);
PAINT MONO (-4072 3400);
FORCEPROP 2 LAST $XR0 158 
J 0
(-3952 3400);
DISPLAY 0.638298 (-3952 3400);
PAINT MONO (-3952 3400);
FORCEPROP 2 LAST $XR1 176 
J 0
(-4072 3400);
DISPLAY 0.638298 (-4072 3400);
PAINT MONO (-4072 3400);
FORCEPROP 1 LAST COMMENT_BODY TRUE
J 0
(-3575 3300);
DISPLAY 0.872340 (-3575 3300);
PAINT GREEN (-3575 3300);
DISPLAY INVISIBLE (-3575 3300);
FORCEPROP 1 LAST OFFPAGE TRUE
J 0
(-3375 3275);
DISPLAY 0.872340 (-3375 3275);
PAINT GREEN (-3375 3275);
DISPLAY INVISIBLE (-3375 3275);
FORCEPROP 2 LAST PATH I272
J 0
(-3650 3475);
DISPLAY 1.021277 (-3650 3475);
PAINT ORANGE (-3650 3475);
DISPLAY INVISIBLE (-3650 3475);
FORCEPROP 2 LAST CDS_LIB mstr_standard
J 0
(-3700 3400);
PAINT ORANGE (-3700 3400);
DISPLAY INVISIBLE (-3700 3400);
FORCEADD OFFPAGE..5
(-3700 3350);
FORCEPROP 2 LAST $XR1 158 
J 0
(-3985 3314);
DISPLAY 0.638298 (-3985 3314);
PAINT MONO (-3985 3314);
FORCEPROP 2 LAST $XR0 176 
J 0
(-3985 3350);
DISPLAY 0.638298 (-3985 3350);
PAINT MONO (-3985 3350);
FORCEPROP 1 LAST OFFPAGE TRUE
J 0
(-3375 3225);
DISPLAY 0.872340 (-3375 3225);
PAINT GREEN (-3375 3225);
DISPLAY INVISIBLE (-3375 3225);
FORCEPROP 2 LAST CDS_LIB mstr_standard
J 0
(-3700 3350);
PAINT ORANGE (-3700 3350);
DISPLAY INVISIBLE (-3700 3350);
FORCEPROP 2 LAST PATH I273
J 0
(-3650 3425);
DISPLAY 1.021277 (-3650 3425);
PAINT ORANGE (-3650 3425);
DISPLAY INVISIBLE (-3650 3425);
FORCEPROP 1 LAST COMMENT_BODY TRUE
J 0
(-3600 3275);
DISPLAY 0.872340 (-3600 3275);
PAINT GREEN (-3600 3275);
DISPLAY INVISIBLE (-3600 3275);
FORCEADD OFFPAGE..5
(-3725 3800);
FORCEPROP 2 LAST $XR0 158 
J 0
(-3980 3800);
DISPLAY 0.638298 (-3980 3800);
PAINT MONO (-3980 3800);
FORCEPROP 1 LAST OFFPAGE TRUE
J 0
(-3400 3675);
DISPLAY 0.872340 (-3400 3675);
PAINT GREEN (-3400 3675);
DISPLAY INVISIBLE (-3400 3675);
FORCEPROP 2 LAST PATH I274
J 0
(-3675 3875);
DISPLAY 1.021277 (-3675 3875);
PAINT ORANGE (-3675 3875);
DISPLAY INVISIBLE (-3675 3875);
FORCEPROP 2 LAST CDS_LIB mstr_standard
J 0
(-3725 3800);
PAINT ORANGE (-3725 3800);
DISPLAY INVISIBLE (-3725 3800);
FORCEPROP 1 LAST COMMENT_BODY TRUE
J 0
(-3625 3725);
DISPLAY 0.872340 (-3625 3725);
PAINT GREEN (-3625 3725);
DISPLAY INVISIBLE (-3625 3725);
FORCEADD OFFPAGE..1
(-3725 3850);
FORCEPROP 2 LAST $XR0 158 
J 0
(-3977 3850);
DISPLAY 0.638298 (-3977 3850);
PAINT MONO (-3977 3850);
FORCEPROP 1 LAST OFFPAGE TRUE
J 0
(-3400 3725);
DISPLAY 0.872340 (-3400 3725);
PAINT GREEN (-3400 3725);
DISPLAY INVISIBLE (-3400 3725);
FORCEPROP 2 LAST CDS_LIB mstr_standard
J 0
(-3725 3850);
PAINT ORANGE (-3725 3850);
DISPLAY INVISIBLE (-3725 3850);
FORCEPROP 2 LAST PATH I275
J 0
(-3675 3925);
DISPLAY 1.021277 (-3675 3925);
PAINT ORANGE (-3675 3925);
DISPLAY INVISIBLE (-3675 3925);
FORCEPROP 1 LAST COMMENT_BODY TRUE
J 0
(-3600 3750);
DISPLAY 0.872340 (-3600 3750);
PAINT GREEN (-3600 3750);
DISPLAY INVISIBLE (-3600 3750);
FORCEADD RES..1
R 1
(-3000 1475);
FORCEPROP 1 LAST LOCATION R9T8
J 0
(-2925 1475);
DISPLAY 0.617021 (-2925 1475);
PAINT AQUA (-2925 1475);
FORCEPROP 1 LAST PART_NUMBER G21497-005
R 1
J 0
(-2800 1375);
DISPLAY 0.617021 (-2800 1375);
PAINT BLUE (-2800 1375);
FORCEPROP 1 LAST PACK_TYPE 0402
R 1
J 0
(-2675 1425);
DISPLAY 0.617021 (-2675 1425);
PAINT SKYBLUE (-2675 1425);
FORCEPROP 1 LAST TOLERANCE 5%
R 1
J 0
(-2950 1525);
DISPLAY 0.617021 (-2950 1525);
PAINT SKYBLUE (-2950 1525);
FORCEPROP 1 LAST WATTAGE 1/16W
R 1
J 2
(-2950 1350);
DISPLAY 0.617021 (-2950 1350);
PAINT SKYBLUE (-2950 1350);
FORCEPROP 1 LAST VALUE 0.0
R 1
J 2
(-2950 1450);
DISPLAY 0.617021 (-2950 1450);
PAINT SKYBLUE (-2950 1450);
FORCEPROP 2 LAST CDS_LIB mstr_discrete
R 1
J 0
(-3000 1475);
PAINT MONO (-3000 1475);
DISPLAY INVISIBLE (-3000 1475);
FORCEPROP 1 LAST PATH I278
R 1
J 0
(-3150 1425);
DISPLAY 0.978723 (-3150 1425);
PAINT WHITE (-3150 1425);
DISPLAY INVISIBLE (-3150 1425);
FORCEPROP 1 LAST MATERIAL CHIP
R 1
J 0
(-2725 1425);
DISPLAY 0.617021 (-2725 1425);
PAINT SKYBLUE (-2725 1425);
DISPLAY INVISIBLE (-2725 1425);
FORCEPROP 1 LASTPIN (-3000 1375) $PN 1
R 1
J 0
(-3012 1387);
DISPLAY 0.787234 (-3012 1387);
PAINT ORANGE (-3012 1387);
DISPLAY INVISIBLE (-3012 1387);
FORCEPROP 1 LASTPIN (-3000 1575) $PN 2
R 1
J 0
(-3012 1537);
DISPLAY 0.787234 (-3012 1537);
PAINT ORANGE (-3012 1537);
DISPLAY INVISIBLE (-3012 1537);
FORCEADD RES..1
(-2375 3850);
FORCEPROP 1 LAST MATERIAL CHIP
J 0
(-2575 3850);
DISPLAY 0.617021 (-2575 3850);
PAINT SKYBLUE (-2575 3850);
FORCEPROP 1 LAST WATTAGE 1/16W
J 2
(-2525 3800);
DISPLAY 0.617021 (-2525 3800);
PAINT SKYBLUE (-2525 3800);
FORCEPROP 1 LAST VALUE 0.0
J 2
(-2450 3800);
DISPLAY 0.617021 (-2450 3800);
PAINT SKYBLUE (-2450 3800);
FORCEPROP 1 LAST LOCATION R9F67
J 0
(-2425 3900);
DISPLAY 0.617021 (-2425 3900);
PAINT AQUA (-2425 3900);
FORCEPROP 1 LAST TOLERANCE 5%
J 0
(-2225 3800);
DISPLAY 0.617021 (-2225 3800);
PAINT SKYBLUE (-2225 3800);
FORCEPROP 1 LAST PART_NUMBER G21497-005
J 0
(-2300 3850);
DISPLAY 0.617021 (-2300 3850);
PAINT BLUE (-2300 3850);
FORCEPROP 1 LAST PATH I279
J 0
(-2425 4000);
DISPLAY 0.978723 (-2425 4000);
PAINT WHITE (-2425 4000);
DISPLAY INVISIBLE (-2425 4000);
FORCEPROP 0 LAST CDS_SEC 1
J 0
(-2425 3950);
PAINT MONO (-2425 3950);
DISPLAY INVISIBLE (-2425 3950);
FORCEPROP 0 LAST $SEC 1
J 0
(-2425 3950);
PAINT MONO (-2425 3950);
DISPLAY INVISIBLE (-2425 3950);
FORCEPROP 1 LASTPIN (-2475 3850) $PN 1
J 0
(-2463 3862);
DISPLAY 0.787234 (-2463 3862);
PAINT ORANGE (-2463 3862);
DISPLAY INVISIBLE (-2463 3862);
FORCEPROP 2 LAST CDS_LIB mstr_discrete
J 0
(-2375 3850);
PAINT ORANGE (-2375 3850);
DISPLAY INVISIBLE (-2375 3850);
FORCEPROP 1 LAST PACK_TYPE 0402
J 0
(-2125 3700);
DISPLAY 0.617021 (-2125 3700);
PAINT SKYBLUE (-2125 3700);
DISPLAY INVISIBLE (-2125 3700);
FORCEPROP 1 LASTPIN (-2275 3850) $PN 2
J 0
(-2313 3862);
DISPLAY 0.787234 (-2313 3862);
PAINT ORANGE (-2313 3862);
DISPLAY INVISIBLE (-2313 3862);
FORCEPROP 0 LAST ROOM UART_MUX
J 0
(-2425 4000);
DISPLAY 1.021277 (-2425 4000);
PAINT ORANGE (-2425 4000);
DISPLAY INVISIBLE (-2425 4000);
FORCEPROP 0 LAST CDS_LOCATION R9F67
J 0
(-2425 3950);
PAINT MONO (-2425 3950);
DISPLAY INVISIBLE (-2425 3950);
FORCEADD RES..1
(-2350 3400);
FORCEPROP 1 LAST WATTAGE 1/16W
J 2
(-2500 3350);
DISPLAY 0.617021 (-2500 3350);
PAINT SKYBLUE (-2500 3350);
FORCEPROP 1 LAST LOCATION R9F70
J 0
(-2375 3475);
DISPLAY 0.617021 (-2375 3475);
PAINT AQUA (-2375 3475);
FORCEPROP 1 LASTPIN (-2450 3400) $PN 1
J 0
(-2438 3412);
DISPLAY 0.617021 (-2438 3412);
PAINT ORANGE (-2438 3412);
FORCEPROP 1 LAST MATERIAL EMPTY
J 0
(-2600 3400);
DISPLAY 0.617021 (-2600 3400);
PAINT RED (-2600 3400);
FORCEPROP 1 LAST VALUE 0.0
J 2
(-2025 3350);
DISPLAY 0.617021 (-2025 3350);
PAINT SKYBLUE (-2025 3350);
FORCEPROP 1 LASTPIN (-2250 3400) $PN 2
J 0
(-2288 3412);
DISPLAY 0.617021 (-2288 3412);
PAINT ORANGE (-2288 3412);
FORCEPROP 1 LAST PART_NUMBER G21497-005
J 0
(-2250 3400);
DISPLAY 0.617021 (-2250 3400);
PAINT BLUE (-2250 3400);
FORCEPROP 1 LAST TOLERANCE 5%
J 0
(-2200 3350);
DISPLAY 0.617021 (-2200 3350);
PAINT SKYBLUE (-2200 3350);
FORCEPROP 1 LAST PATH I280
J 0
(-2400 3550);
DISPLAY 0.978723 (-2400 3550);
PAINT WHITE (-2400 3550);
DISPLAY INVISIBLE (-2400 3550);
FORCEPROP 1 LAST PACK_TYPE 0402
J 0
(-2100 3250);
DISPLAY 0.617021 (-2100 3250);
PAINT SKYBLUE (-2100 3250);
DISPLAY INVISIBLE (-2100 3250);
FORCEPROP 0 LAST ROOM UART_MUX
J 0
(-2400 3550);
DISPLAY 1.021277 (-2400 3550);
PAINT ORANGE (-2400 3550);
DISPLAY INVISIBLE (-2400 3550);
FORCEPROP 2 LAST SEC_TYPE 0402
J 0
(-2400 3600);
DISPLAY 1.021277 (-2400 3600);
PAINT ORANGE (-2400 3600);
DISPLAY INVISIBLE (-2400 3600);
FORCEPROP 0 LAST SEC 1
J 0
(-2400 3500);
DISPLAY 0.680851 (-2400 3500);
PAINT MONO (-2400 3500);
DISPLAY INVISIBLE (-2400 3500);
FORCEPROP 2 LAST CDS_LIB mstr_discrete
J 0
(-2350 3400);
PAINT ORANGE (-2350 3400);
DISPLAY INVISIBLE (-2350 3400);
FORCEPROP 0 LAST CDS_SEC 1
J 0
(-2425 3550);
PAINT MONO (-2425 3550);
DISPLAY INVISIBLE (-2425 3550);
FORCEPROP 0 LAST CDS_LOCATION R9F70
J 0
(-2425 3550);
PAINT MONO (-2425 3550);
DISPLAY INVISIBLE (-2425 3550);
FORCEADD RES..1
(-2775 3800);
FORCEPROP 1 LAST LOCATION R9F64
J 0
(-2825 3850);
DISPLAY 0.617021 (-2825 3850);
PAINT AQUA (-2825 3850);
FORCEPROP 1 LASTPIN (-2875 3800) $PN 1
J 0
(-2863 3812);
DISPLAY 0.617021 (-2863 3812);
PAINT ORANGE (-2863 3812);
FORCEPROP 1 LAST VALUE 0.0
J 2
(-3100 3900);
DISPLAY 0.617021 (-3100 3900);
PAINT SKYBLUE (-3100 3900);
FORCEPROP 1 LAST MATERIAL CHIP
J 0
(-2975 3800);
DISPLAY 0.617021 (-2975 3800);
PAINT SKYBLUE (-2975 3800);
FORCEPROP 1 LASTPIN (-2675 3800) $PN 2
J 0
(-2713 3812);
DISPLAY 0.617021 (-2713 3812);
PAINT ORANGE (-2713 3812);
FORCEPROP 1 LAST PART_NUMBER G21497-005
J 0
(-3175 3850);
DISPLAY 0.617021 (-3175 3850);
PAINT BLUE (-3175 3850);
FORCEPROP 1 LAST PATH I281
J 0
(-2825 3950);
DISPLAY 0.978723 (-2825 3950);
PAINT WHITE (-2825 3950);
DISPLAY INVISIBLE (-2825 3950);
FORCEPROP 0 LAST CDS_SEC 1
J 0
(-3100 3950);
PAINT MONO (-3100 3950);
DISPLAY INVISIBLE (-3100 3950);
FORCEPROP 0 LAST SEC 1
J 0
(-3100 3950);
DISPLAY 0.680851 (-3100 3950);
PAINT MONO (-3100 3950);
DISPLAY INVISIBLE (-3100 3950);
FORCEPROP 1 LAST TOLERANCE 5%
J 0
(-2950 4000);
DISPLAY 0.617021 (-2950 4000);
PAINT SKYBLUE (-2950 4000);
DISPLAY INVISIBLE (-2950 4000);
FORCEPROP 2 LAST CDS_LIB mstr_discrete
J 0
(-2775 3800);
PAINT ORANGE (-2775 3800);
DISPLAY INVISIBLE (-2775 3800);
FORCEPROP 1 LAST WATTAGE 1/16W
J 2
(-2850 3850);
DISPLAY 0.617021 (-2850 3850);
PAINT SKYBLUE (-2850 3850);
DISPLAY INVISIBLE (-2850 3850);
FORCEPROP 0 LAST ROOM UART_MUX
J 0
(-3100 4000);
DISPLAY 1.021277 (-3100 4000);
PAINT ORANGE (-3100 4000);
DISPLAY INVISIBLE (-3100 4000);
FORCEPROP 2 LAST SEC_TYPE 0402
J 0
(-2825 4000);
DISPLAY 1.021277 (-2825 4000);
PAINT ORANGE (-2825 4000);
DISPLAY INVISIBLE (-2825 4000);
FORCEPROP 1 LAST PACK_TYPE 0402
J 0
(-2525 3650);
DISPLAY 0.617021 (-2525 3650);
PAINT SKYBLUE (-2525 3650);
DISPLAY INVISIBLE (-2525 3650);
FORCEPROP 0 LAST CDS_LOCATION R9F64
J 0
(-3100 3950);
PAINT MONO (-3100 3950);
DISPLAY INVISIBLE (-3100 3950);
FORCEADD RES..1
(-2725 3350);
FORCEPROP 1 LAST VALUE 0.0
J 2
(-3025 3250);
DISPLAY 0.617021 (-3025 3250);
PAINT SKYBLUE (-3025 3250);
FORCEPROP 1 LAST MATERIAL EMPTY
J 0
(-2975 3350);
DISPLAY 0.617021 (-2975 3350);
PAINT RED (-2975 3350);
FORCEPROP 1 LASTPIN (-2825 3350) $PN 1
J 0
(-2813 3362);
DISPLAY 0.617021 (-2813 3362);
PAINT ORANGE (-2813 3362);
FORCEPROP 1 LAST LOCATION R9F63
J 0
(-2775 3450);
DISPLAY 0.617021 (-2775 3450);
PAINT AQUA (-2775 3450);
FORCEPROP 1 LAST PART_NUMBER G21497-005
J 0
(-3225 3350);
DISPLAY 0.617021 (-3225 3350);
PAINT BLUE (-3225 3350);
FORCEPROP 1 LASTPIN (-2625 3350) $PN 2
J 0
(-2663 3362);
DISPLAY 0.617021 (-2663 3362);
PAINT ORANGE (-2663 3362);
FORCEPROP 1 LAST PATH I282
J 0
(-2775 3500);
DISPLAY 0.978723 (-2775 3500);
PAINT WHITE (-2775 3500);
DISPLAY INVISIBLE (-2775 3500);
FORCEPROP 1 LAST PACK_TYPE 0402
J 0
(-2475 3200);
DISPLAY 0.617021 (-2475 3200);
PAINT SKYBLUE (-2475 3200);
DISPLAY INVISIBLE (-2475 3200);
FORCEPROP 2 LAST CDS_LIB mstr_discrete
J 0
(-2725 3350);
PAINT ORANGE (-2725 3350);
DISPLAY INVISIBLE (-2725 3350);
FORCEPROP 0 LAST SEC 1
J 0
(-2775 3450);
DISPLAY 0.680851 (-2775 3450);
PAINT MONO (-2775 3450);
DISPLAY INVISIBLE (-2775 3450);
FORCEPROP 2 LAST SEC_TYPE 0402
J 0
(-2775 3550);
DISPLAY 1.021277 (-2775 3550);
PAINT ORANGE (-2775 3550);
DISPLAY INVISIBLE (-2775 3550);
FORCEPROP 0 LAST ROOM UART_MUX
J 0
(-2775 3500);
DISPLAY 1.021277 (-2775 3500);
PAINT ORANGE (-2775 3500);
DISPLAY INVISIBLE (-2775 3500);
FORCEPROP 1 LAST WATTAGE 1/16W
J 2
(-2800 3400);
DISPLAY 0.617021 (-2800 3400);
PAINT SKYBLUE (-2800 3400);
DISPLAY INVISIBLE (-2800 3400);
FORCEPROP 1 LAST TOLERANCE 5%
J 0
(-2900 3550);
DISPLAY 0.617021 (-2900 3550);
PAINT SKYBLUE (-2900 3550);
DISPLAY INVISIBLE (-2900 3550);
FORCEPROP 0 LAST CDS_SEC 1
J 0
(-2775 3500);
PAINT MONO (-2775 3500);
DISPLAY INVISIBLE (-2775 3500);
FORCEPROP 0 LAST CDS_LOCATION R9F63
J 0
(-2775 3500);
PAINT MONO (-2775 3500);
DISPLAY INVISIBLE (-2775 3500);
FORCEADD GND..1
(50 2375);
FORCEPROP 3 LASTPIN (50 2425) SIG_NAME GND\g
J 0
(60 2435);
DISPLAY 0.659574 (60 2435);
PAINT MONO (60 2435);
DISPLAY INVISIBLE (60 2435);
FORCEPROP 1 LAST HDL_POWER GND
J 0
(50 2525);
DISPLAY 0.872340 (50 2525);
PAINT GREEN (50 2525);
DISPLAY INVISIBLE (50 2525);
FORCEPROP 1 LAST PATH I45
J 0
(125 2375);
DISPLAY 0.872340 (125 2375);
PAINT AQUA (125 2375);
DISPLAY INVISIBLE (125 2375);
FORCEPROP 1 LAST BODY_TYPE PLUMBING
J 0
(5 2332);
DISPLAY 0.340426 (5 2332);
PAINT GREEN (5 2332);
DISPLAY INVISIBLE (5 2332);
FORCEPROP 2 LAST CDS_LIB mstr_symbols
J 0
(50 2375);
PAINT MONO (50 2375);
DISPLAY INVISIBLE (50 2375);
FORCEPROP 1 LAST SIZE 1B
J 0
(125 2325);
DISPLAY 0.872340 (125 2325);
PAINT GREEN (125 2325);
DISPLAY INVISIBLE (125 2325);
FORCEPROP 1 LAST VOLTAGE 0
J 0
(50 2375);
PAINT SKYBLUE (50 2375);
DISPLAY INVISIBLE (50 2375);
FORCEPROP 2 LAST BOM_COST NT_BASE_VRD
J 0
(-250 2450);
DISPLAY 0.617021 (-250 2450);
PAINT ORANGE (-250 2450);
DISPLAY INVISIBLE (-250 2450);
FORCEPROP 2 LAST ROOM P2V5_LAN_AUX_VR
J 0
(-250 2450);
DISPLAY 0.617021 (-250 2450);
PAINT ORANGE (-250 2450);
DISPLAY INVISIBLE (-250 2450);
FORCEADD TAP..1
R 2
(-1600 4700);
FORCEPROP 3 LASTPIN (-1550 4700) SIG_NAME P3E_CPU1_PE3_MP_RXP<0>
J 0
(-1540 4710);
DISPLAY 0.659574 (-1540 4710);
PAINT MONO (-1540 4710);
DISPLAY INVISIBLE (-1540 4710);
FORCEPROP 1 LASTPIN (-1550 4700) BN 0
J 2
(-1538 4708);
DISPLAY 0.617021 (-1538 4708);
PAINT GREEN (-1538 4708);
FORCEPROP 2 LAST CDS_LIB mstr_standard
J 0
(-1600 4700);
PAINT MONO (-1600 4700);
DISPLAY INVISIBLE (-1600 4700);
FORCEPROP 1 LAST BODY_TYPE PLUMBING
J 2
(-1600 4750);
DISPLAY 1.446809 (-1600 4750);
PAINT GREEN (-1600 4750);
DISPLAY INVISIBLE (-1600 4750);
FORCEPROP 1 LAST PATH I47
J 2
(-1598 4700);
DISPLAY 0.872340 (-1598 4700);
PAINT GREEN (-1598 4700);
DISPLAY INVISIBLE (-1598 4700);
FORCEPROP 1 LAST HDL_TAP TRUE
J 2
(-1925 4575);
DISPLAY 1.446809 (-1925 4575);
PAINT GREEN (-1925 4575);
DISPLAY INVISIBLE (-1925 4575);
FORCEADD TAP..1
R 2
(-1600 4550);
FORCEPROP 3 LASTPIN (-1550 4550) SIG_NAME P3E_CPU1_PE3_MP_RXP<1>
J 0
(-1540 4560);
DISPLAY 0.659574 (-1540 4560);
PAINT MONO (-1540 4560);
DISPLAY INVISIBLE (-1540 4560);
FORCEPROP 1 LASTPIN (-1550 4550) BN 1
J 2
(-1538 4558);
DISPLAY 0.617021 (-1538 4558);
PAINT GREEN (-1538 4558);
FORCEPROP 1 LAST BODY_TYPE PLUMBING
J 2
(-1600 4600);
DISPLAY 1.446809 (-1600 4600);
PAINT GREEN (-1600 4600);
DISPLAY INVISIBLE (-1600 4600);
FORCEPROP 1 LAST PATH I48
J 2
(-1598 4550);
DISPLAY 0.872340 (-1598 4550);
PAINT GREEN (-1598 4550);
DISPLAY INVISIBLE (-1598 4550);
FORCEPROP 2 LAST CDS_LIB mstr_standard
J 0
(-1600 4550);
PAINT MONO (-1600 4550);
DISPLAY INVISIBLE (-1600 4550);
FORCEPROP 1 LAST HDL_TAP TRUE
J 2
(-1925 4425);
DISPLAY 1.446809 (-1925 4425);
PAINT GREEN (-1925 4425);
DISPLAY INVISIBLE (-1925 4425);
FORCEADD TAP..1
R 2
(-1850 4750);
FORCEPROP 3 LASTPIN (-1800 4750) SIG_NAME P3E_CPU1_PE3_MP_RXN<0>
J 0
(-1790 4760);
DISPLAY 0.659574 (-1790 4760);
PAINT MONO (-1790 4760);
DISPLAY INVISIBLE (-1790 4760);
FORCEPROP 1 LASTPIN (-1800 4750) BN 0
J 2
(-1788 4758);
DISPLAY 0.617021 (-1788 4758);
PAINT GREEN (-1788 4758);
FORCEPROP 2 LAST CDS_LIB mstr_standard
J 0
(-1850 4750);
PAINT MONO (-1850 4750);
DISPLAY INVISIBLE (-1850 4750);
FORCEPROP 1 LAST BODY_TYPE PLUMBING
J 2
(-1850 4800);
DISPLAY 1.446809 (-1850 4800);
PAINT GREEN (-1850 4800);
DISPLAY INVISIBLE (-1850 4800);
FORCEPROP 1 LAST PATH I49
J 2
(-1848 4750);
DISPLAY 0.872340 (-1848 4750);
PAINT GREEN (-1848 4750);
DISPLAY INVISIBLE (-1848 4750);
FORCEPROP 1 LAST HDL_TAP TRUE
J 2
(-2175 4625);
DISPLAY 1.446809 (-2175 4625);
PAINT GREEN (-2175 4625);
DISPLAY INVISIBLE (-2175 4625);
FORCEADD TAP..1
R 2
(-1850 4600);
FORCEPROP 3 LASTPIN (-1800 4600) SIG_NAME P3E_CPU1_PE3_MP_RXN<1>
J 0
(-1790 4610);
DISPLAY 0.659574 (-1790 4610);
PAINT MONO (-1790 4610);
DISPLAY INVISIBLE (-1790 4610);
FORCEPROP 1 LASTPIN (-1800 4600) BN 1
J 2
(-1788 4608);
DISPLAY 0.617021 (-1788 4608);
PAINT GREEN (-1788 4608);
FORCEPROP 1 LAST BODY_TYPE PLUMBING
J 2
(-1850 4650);
DISPLAY 1.446809 (-1850 4650);
PAINT GREEN (-1850 4650);
DISPLAY INVISIBLE (-1850 4650);
FORCEPROP 1 LAST PATH I50
J 2
(-1848 4600);
DISPLAY 0.872340 (-1848 4600);
PAINT GREEN (-1848 4600);
DISPLAY INVISIBLE (-1848 4600);
FORCEPROP 2 LAST CDS_LIB mstr_standard
J 0
(-1850 4600);
PAINT MONO (-1850 4600);
DISPLAY INVISIBLE (-1850 4600);
FORCEPROP 1 LAST HDL_TAP TRUE
J 2
(-2175 4475);
DISPLAY 1.446809 (-2175 4475);
PAINT GREEN (-2175 4475);
DISPLAY INVISIBLE (-2175 4475);
FORCEADD TAP..1
R 2
(-1600 4150);
FORCEPROP 3 LASTPIN (-1550 4150) SIG_NAME P3E_CPU1_PE3_MP_RXP<3>
J 0
(-1540 4160);
DISPLAY 0.659574 (-1540 4160);
PAINT MONO (-1540 4160);
DISPLAY INVISIBLE (-1540 4160);
FORCEPROP 1 LASTPIN (-1550 4150) BN 3
J 2
(-1538 4158);
DISPLAY 0.617021 (-1538 4158);
PAINT GREEN (-1538 4158);
FORCEPROP 1 LAST PATH I53
J 2
(-1598 4150);
DISPLAY 0.872340 (-1598 4150);
PAINT GREEN (-1598 4150);
DISPLAY INVISIBLE (-1598 4150);
FORCEPROP 1 LAST BODY_TYPE PLUMBING
J 2
(-1600 4200);
DISPLAY 1.446809 (-1600 4200);
PAINT GREEN (-1600 4200);
DISPLAY INVISIBLE (-1600 4200);
FORCEPROP 2 LAST CDS_LIB mstr_standard
J 0
(-1600 4150);
PAINT MONO (-1600 4150);
DISPLAY INVISIBLE (-1600 4150);
FORCEPROP 1 LAST HDL_TAP TRUE
J 2
(-1925 4025);
DISPLAY 1.446809 (-1925 4025);
PAINT GREEN (-1925 4025);
DISPLAY INVISIBLE (-1925 4025);
FORCEADD TAP..1
R 2
(-1600 4000);
FORCEPROP 3 LASTPIN (-1550 4000) SIG_NAME P3E_CPU1_PE3_MP_RXP<4>
J 0
(-1540 4010);
DISPLAY 0.659574 (-1540 4010);
PAINT MONO (-1540 4010);
DISPLAY INVISIBLE (-1540 4010);
FORCEPROP 1 LASTPIN (-1550 4000) BN 4
J 2
(-1538 4008);
DISPLAY 0.617021 (-1538 4008);
PAINT GREEN (-1538 4008);
FORCEPROP 1 LAST BODY_TYPE PLUMBING
J 2
(-1600 4050);
DISPLAY 1.446809 (-1600 4050);
PAINT GREEN (-1600 4050);
DISPLAY INVISIBLE (-1600 4050);
FORCEPROP 1 LAST PATH I54
J 2
(-1598 4000);
DISPLAY 0.872340 (-1598 4000);
PAINT GREEN (-1598 4000);
DISPLAY INVISIBLE (-1598 4000);
FORCEPROP 2 LAST CDS_LIB mstr_standard
J 0
(-1600 4000);
PAINT MONO (-1600 4000);
DISPLAY INVISIBLE (-1600 4000);
FORCEPROP 1 LAST HDL_TAP TRUE
J 2
(-1925 3875);
DISPLAY 1.446809 (-1925 3875);
PAINT GREEN (-1925 3875);
DISPLAY INVISIBLE (-1925 3875);
FORCEADD TAP..1
R 2
(-1850 4200);
FORCEPROP 3 LASTPIN (-1800 4200) SIG_NAME P3E_CPU1_PE3_MP_RXN<3>
J 0
(-1790 4210);
DISPLAY 0.659574 (-1790 4210);
PAINT MONO (-1790 4210);
DISPLAY INVISIBLE (-1790 4210);
FORCEPROP 1 LASTPIN (-1800 4200) BN 3
J 2
(-1788 4208);
DISPLAY 0.617021 (-1788 4208);
PAINT GREEN (-1788 4208);
FORCEPROP 1 LAST PATH I57
J 2
(-1848 4200);
DISPLAY 0.872340 (-1848 4200);
PAINT GREEN (-1848 4200);
DISPLAY INVISIBLE (-1848 4200);
FORCEPROP 2 LAST CDS_LIB mstr_standard
J 0
(-1850 4200);
PAINT MONO (-1850 4200);
DISPLAY INVISIBLE (-1850 4200);
FORCEPROP 1 LAST BODY_TYPE PLUMBING
J 2
(-1850 4250);
DISPLAY 1.446809 (-1850 4250);
PAINT GREEN (-1850 4250);
DISPLAY INVISIBLE (-1850 4250);
FORCEPROP 1 LAST HDL_TAP TRUE
J 2
(-2175 4075);
DISPLAY 1.446809 (-2175 4075);
PAINT GREEN (-2175 4075);
DISPLAY INVISIBLE (-2175 4075);
FORCEADD TAP..1
R 2
(-1850 4050);
FORCEPROP 3 LASTPIN (-1800 4050) SIG_NAME P3E_CPU1_PE3_MP_RXN<4>
J 0
(-1790 4060);
DISPLAY 0.659574 (-1790 4060);
PAINT MONO (-1790 4060);
DISPLAY INVISIBLE (-1790 4060);
FORCEPROP 1 LASTPIN (-1800 4050) BN 4
J 2
(-1788 4058);
DISPLAY 0.617021 (-1788 4058);
PAINT GREEN (-1788 4058);
FORCEPROP 1 LAST BODY_TYPE PLUMBING
J 2
(-1850 4100);
DISPLAY 1.446809 (-1850 4100);
PAINT GREEN (-1850 4100);
DISPLAY INVISIBLE (-1850 4100);
FORCEPROP 1 LAST PATH I58
J 2
(-1848 4050);
DISPLAY 0.872340 (-1848 4050);
PAINT GREEN (-1848 4050);
DISPLAY INVISIBLE (-1848 4050);
FORCEPROP 2 LAST CDS_LIB mstr_standard
J 0
(-1850 4050);
PAINT MONO (-1850 4050);
DISPLAY INVISIBLE (-1850 4050);
FORCEPROP 1 LAST HDL_TAP TRUE
J 2
(-2175 3925);
DISPLAY 1.446809 (-2175 3925);
PAINT GREEN (-2175 3925);
DISPLAY INVISIBLE (-2175 3925);
FORCEADD TAP..1
R 2
(-1600 3700);
FORCEPROP 3 LASTPIN (-1550 3700) SIG_NAME P3E_CPU1_PE3_MP_RXP<6>
J 0
(-1540 3710);
DISPLAY 0.659574 (-1540 3710);
PAINT MONO (-1540 3710);
DISPLAY INVISIBLE (-1540 3710);
FORCEPROP 1 LASTPIN (-1550 3700) BN 6
J 2
(-1538 3708);
DISPLAY 0.617021 (-1538 3708);
PAINT GREEN (-1538 3708);
FORCEPROP 1 LAST PATH I67
J 2
(-1598 3700);
DISPLAY 0.872340 (-1598 3700);
PAINT GREEN (-1598 3700);
DISPLAY INVISIBLE (-1598 3700);
FORCEPROP 1 LAST BODY_TYPE PLUMBING
J 2
(-1600 3750);
DISPLAY 1.446809 (-1600 3750);
PAINT GREEN (-1600 3750);
DISPLAY INVISIBLE (-1600 3750);
FORCEPROP 2 LAST CDS_LIB mstr_standard
J 0
(-1600 3700);
PAINT MONO (-1600 3700);
DISPLAY INVISIBLE (-1600 3700);
FORCEPROP 1 LAST HDL_TAP TRUE
J 2
(-1925 3575);
DISPLAY 1.446809 (-1925 3575);
PAINT GREEN (-1925 3575);
DISPLAY INVISIBLE (-1925 3575);
FORCEADD TAP..1
R 2
(-1600 3500);
FORCEPROP 3 LASTPIN (-1550 3500) SIG_NAME P3E_CPU1_PE3_MP_RXP<7>
J 0
(-1540 3510);
DISPLAY 0.659574 (-1540 3510);
PAINT MONO (-1540 3510);
DISPLAY INVISIBLE (-1540 3510);
FORCEPROP 1 LASTPIN (-1550 3500) BN 7
J 2
(-1538 3508);
DISPLAY 0.617021 (-1538 3508);
PAINT GREEN (-1538 3508);
FORCEPROP 1 LAST BODY_TYPE PLUMBING
J 2
(-1600 3550);
DISPLAY 1.446809 (-1600 3550);
PAINT GREEN (-1600 3550);
DISPLAY INVISIBLE (-1600 3550);
FORCEPROP 2 LAST CDS_LIB mstr_standard
J 0
(-1600 3500);
PAINT MONO (-1600 3500);
DISPLAY INVISIBLE (-1600 3500);
FORCEPROP 1 LAST PATH I68
J 2
(-1598 3500);
DISPLAY 0.872340 (-1598 3500);
PAINT GREEN (-1598 3500);
DISPLAY INVISIBLE (-1598 3500);
FORCEPROP 1 LAST HDL_TAP TRUE
J 2
(-1925 3375);
DISPLAY 1.446809 (-1925 3375);
PAINT GREEN (-1925 3375);
DISPLAY INVISIBLE (-1925 3375);
FORCEADD TAP..1
R 2
(-1850 3550);
FORCEPROP 3 LASTPIN (-1800 3550) SIG_NAME P3E_CPU1_PE3_MP_RXN<7>
J 0
(-1790 3560);
DISPLAY 0.659574 (-1790 3560);
PAINT MONO (-1790 3560);
DISPLAY INVISIBLE (-1790 3560);
FORCEPROP 1 LASTPIN (-1800 3550) BN 7
J 2
(-1788 3558);
DISPLAY 0.617021 (-1788 3558);
PAINT GREEN (-1788 3558);
FORCEPROP 1 LAST BODY_TYPE PLUMBING
J 2
(-1850 3600);
DISPLAY 1.446809 (-1850 3600);
PAINT GREEN (-1850 3600);
DISPLAY INVISIBLE (-1850 3600);
FORCEPROP 1 LAST PATH I69
J 2
(-1848 3550);
DISPLAY 0.872340 (-1848 3550);
PAINT GREEN (-1848 3550);
DISPLAY INVISIBLE (-1848 3550);
FORCEPROP 2 LAST CDS_LIB mstr_standard
J 0
(-1850 3550);
PAINT MONO (-1850 3550);
DISPLAY INVISIBLE (-1850 3550);
FORCEPROP 1 LAST HDL_TAP TRUE
J 2
(-2175 3425);
DISPLAY 1.446809 (-2175 3425);
PAINT GREEN (-2175 3425);
DISPLAY INVISIBLE (-2175 3425);
FORCEADD TAP..1
R 2
(-1850 3650);
FORCEPROP 3 LASTPIN (-1800 3650) SIG_NAME P3E_CPU1_PE3_MP_RXN<6>
J 0
(-1790 3660);
DISPLAY 0.659574 (-1790 3660);
PAINT MONO (-1790 3660);
DISPLAY INVISIBLE (-1790 3660);
FORCEPROP 1 LASTPIN (-1800 3650) BN 6
J 2
(-1788 3658);
DISPLAY 0.617021 (-1788 3658);
PAINT GREEN (-1788 3658);
FORCEPROP 1 LAST PATH I70
J 2
(-1848 3650);
DISPLAY 0.872340 (-1848 3650);
PAINT GREEN (-1848 3650);
DISPLAY INVISIBLE (-1848 3650);
FORCEPROP 1 LAST BODY_TYPE PLUMBING
J 2
(-1850 3700);
DISPLAY 1.446809 (-1850 3700);
PAINT GREEN (-1850 3700);
DISPLAY INVISIBLE (-1850 3700);
FORCEPROP 2 LAST CDS_LIB mstr_standard
J 0
(-1850 3650);
PAINT MONO (-1850 3650);
DISPLAY INVISIBLE (-1850 3650);
FORCEPROP 1 LAST HDL_TAP TRUE
J 2
(-2175 3525);
DISPLAY 1.446809 (-2175 3525);
PAINT GREEN (-2175 3525);
DISPLAY INVISIBLE (-2175 3525);
FORCEADD DNS..2
(-2720 3345);
PAINT RED (-2720 3345);
FORCEPROP 1 LAST COMMENT_BODY TRUE
R 1
J 0
(-2645 3120);
DISPLAY 0.872340 (-2645 3120);
PAINT GREEN (-2645 3120);
DISPLAY INVISIBLE (-2645 3120);
FORCEPROP 2 LAST CDS_LIB mstr_misc
J 0
(-2720 3345);
PAINT ORANGE (-2720 3345);
DISPLAY INVISIBLE (-2720 3345);
FORCEADD DNS..2
(-295 870);
PAINT RED (-295 870);
FORCEPROP 2 LAST CDS_LIB mstr_misc
J 0
(-295 870);
PAINT ORANGE (-295 870);
DISPLAY INVISIBLE (-295 870);
FORCEPROP 1 LAST COMMENT_BODY TRUE
R 1
J 0
(-220 645);
DISPLAY 0.872340 (-220 645);
PAINT GREEN (-220 645);
DISPLAY INVISIBLE (-220 645);
FORCEADD CAD_NOTE..1
(775 2675);
FORCEPROP 0 LAST L2 TO CONNECTOR PIN
J 0
(625 2475);
DISPLAY 0.808511 (625 2475);
PAINT ORANGE (625 2475);
FORCEPROP 0 LAST L1 PLACE 0.22UF TX CAPS CLOSE
J 0
(625 2525);
DISPLAY 0.808511 (625 2525);
PAINT ORANGE (625 2525);
FORCEPROP 1 LAST COMMENT_BODY TRUE
J 0
(800 2775);
DISPLAY 0.978723 (800 2775);
PAINT PEACH (800 2775);
DISPLAY INVISIBLE (800 2775);
FORCEPROP 2 LAST CDS_LIB mstr_symbols
J 0
(775 2675);
PAINT MONO (775 2675);
DISPLAY INVISIBLE (775 2675);
FORCEADD CAD_NOTE..1
(-1925 1175);
FORCEPROP 0 LAST L1 PLACE 0.1UF CAP
J 2
(-1700 1050);
DISPLAY 1.021277 (-1700 1050);
PAINT ORANGE (-1700 1050);
FORCEPROP 0 LAST L2 NEXT TO VCC PIN OF
J 2
(-1700 975);
DISPLAY 1.021277 (-1700 975);
PAINT ORANGE (-1700 975);
FORCEPROP 0 LAST L3 74LVC08A
J 2
(-1700 900);
DISPLAY 1.021277 (-1700 900);
PAINT ORANGE (-1700 900);
FORCEPROP 1 LAST COMMENT_BODY TRUE
J 0
(-1900 1275);
DISPLAY 0.978723 (-1900 1275);
PAINT ORANGE (-1900 1275);
DISPLAY INVISIBLE (-1900 1275);
FORCEPROP 2 LAST CDS_LIB mstr_symbols
J 0
(-1925 1175);
PAINT ORANGE (-1925 1175);
DISPLAY INVISIBLE (-1925 1175);
FORCEADD DNS..2
(-2345 3420);
PAINT RED (-2345 3420);
FORCEPROP 1 LAST COMMENT_BODY TRUE
R 1
J 0
(-2270 3195);
DISPLAY 0.872340 (-2270 3195);
PAINT GREEN (-2270 3195);
DISPLAY INVISIBLE (-2270 3195);
FORCEPROP 2 LAST CDS_LIB mstr_misc
J 0
(-2345 3420);
PAINT ORANGE (-2345 3420);
DISPLAY INVISIBLE (-2345 3420);
FORCEADD CAD_NOTE..1
(-3825 4700);
FORCEPROP 0 LAST L3 SPA_MID_DBG_RX_R
J 0
(-3975 4475);
DISPLAY 0.638298 (-3975 4475);
PAINT ORANGE (-3975 4475);
FORCEPROP 0 LAST L2 SPA_MID_DBG_TX_R
J 0
(-3975 4525);
DISPLAY 0.638298 (-3975 4525);
PAINT ORANGE (-3975 4525);
FORCEPROP 0 LAST L1 USE SHARED PADS FOR RESISTORS ON FOLLOWING NETS:
J 0
(-3975 4575);
DISPLAY 0.638298 (-3975 4575);
PAINT ORANGE (-3975 4575);
FORCEPROP 1 LAST COMMENT_BODY TRUE
J 0
(-3800 4800);
DISPLAY 0.978723 (-3800 4800);
PAINT ORANGE (-3800 4800);
DISPLAY INVISIBLE (-3800 4800);
FORCEPROP 2 LAST CDS_LIB mstr_symbols
J 0
(-3825 4700);
PAINT ORANGE (-3825 4700);
DISPLAY INVISIBLE (-3825 4700);
FORCEADD DESIGN_NOTE..1
(-3775 4325);
FORCEPROP 0 LAST L3 NETS FROM AIRMAX B TO AIRMAX A FOR COMPATIBILITY
J 0
(-3975 4100);
DISPLAY 0.638298 (-3975 4100);
PAINT ORANGE (-3975 4100);
FORCEPROP 0 LAST L4 WITH BULLDOG CREEK. WHEN USING WITH BULLDOG
J 0
(-3975 4050);
DISPLAY 0.638298 (-3975 4050);
PAINT ORANGE (-3975 4050);
FORCEPROP 0 LAST L2 AND FAN_PWM_OUT_SYS0_R ARE USED FOR STEERING
J 0
(-3975 4150);
DISPLAY 0.638298 (-3975 4150);
PAINT ORANGE (-3975 4150);
FORCEPROP 0 LAST L5 CREEK, DEPOPULATE THESE RESISTORS.
J 0
(-3975 4000);
DISPLAY 0.638298 (-3975 4000);
PAINT ORANGE (-3975 4000);
FORCEPROP 0 LAST L1 SERIES RESISTORS ON FAN_TACH3, FAN_TACH2, FAN_TACH1
J 0
(-3975 4225);
DISPLAY 0.638298 (-3975 4225);
PAINT ORANGE (-3975 4225);
FORCEPROP 1 LAST COMMENT_BODY TRUE
J 0
(-3750 4425);
DISPLAY 0.978723 (-3750 4425);
PAINT ORANGE (-3750 4425);
DISPLAY INVISIBLE (-3750 4425);
FORCEPROP 2 LAST CDS_LIB mstr_symbols
J 0
(-3775 4325);
PAINT ORANGE (-3775 4325);
DISPLAY INVISIBLE (-3775 4325);
FORCEADD INTEL_CORP_BPAGE..1
(3900 300);
FORCEPROP 1 LAST CDS_CON_LAST_MODIFIED Tue Dec 01 11:52:15 2015
J 0
(2475 625);
PAINT ORANGE (2475 625);
DISPLAY INVISIBLE (2475 625);
FORCEPROP 1 LAST CUSTOM_TXT_CDS <CURRENT_DESIGN_SHEET> OF <TOTAL_DESIGN_SHEETS>
J 0
(3400 325);
PAINT GREEN (3400 325);
FORCEPROP 1 LAST CUSTOM_TXT_CDS <CON_LAST_MODIFIED>
J 0
(1975 650);
PAINT GREEN (1975 650);
FORCEPROP 2 LAST CUSTOM_TXT_CDS <XR_PAGE_TITLE>
J 0
(-3990 5550);
DISPLAY 0.638298 (-3990 5550);
PAINT PINK (-3990 5550);
DISPLAY INVISIBLE (-3990 5550);
FORCEPROP 1 LAST SCH_TITLE AIRMAX 1X8 MID-PLANE CONNECTOR A
J 0
(-4050 350);
DISPLAY 1.212766 (-4050 350);
PAINT ORANGE (-4050 350);
FORCEPROP 1 LAST SCH_REV 2.420
J 0
(3650 450);
DISPLAY 0.978723 (3650 450);
PAINT YELLOW (3650 450);
FORCEPROP 1 LAST SCH_DEPT BESD
J 1
(-550 400);
DISPLAY 1.212766 (-550 400);
PAINT YELLOW (-550 400);
FORCEPROP 1 LAST SCH_NUMBER H4694802
J 0
(2600 450);
DISPLAY 1.212766 (2600 450);
PAINT YELLOW (2600 450);
FORCEPROP 1 LAST SCH_ADDRESS1 2200 Mission College Blvd.
J 0
(-75 425);
DISPLAY 0.617021 (-75 425);
PAINT GREEN (-75 425);
FORCEPROP 1 LAST SCH_ADDRESS2 P.O. BOX 58119
J 0
(-75 375);
DISPLAY 0.617021 (-75 375);
PAINT GREEN (-75 375);
FORCEPROP 1 LAST SCH_ADDRESS3 Santa Clara, CA 95052-8119
J 0
(-75 325);
DISPLAY 0.617021 (-75 325);
PAINT GREEN (-75 325);
FORCEPROP 2 LAST CDS_LIB mstr_symbols
J 0
(3900 300);
PAINT MONO (3900 300);
DISPLAY INVISIBLE (3900 300);
FORCEPROP 1 LAST COMMENT_BODY TRUE
J 0
(3912 312);
DISPLAY 0.468085 (3912 312);
PAINT GREEN (3912 312);
DISPLAY INVISIBLE (3912 312);
FORCEPROP 2 LAST PAGE_BORDER TRUE
J 0
(-3990 5550);
DISPLAY 0.638298 (-3990 5550);
PAINT PINK (-3990 5550);
DISPLAY INVISIBLE (-3990 5550);
FORCEPROP 2 LAST CDS_XR_PAGE_TITLE CR-181 : @BASEBOARD_FAB2_LIB.BASEBOARD_FAB2(SCH_1):PAGE181
J 0
(-3990 5550);
DISPLAY 0.638298 (-3990 5550);
PAINT PINK (-3990 5550);
DISPLAY INVISIBLE (-3990 5550);
WIRE 17 -1 (-1650 4175)(-1650 4025);
WIRE 17 -1 (-1650 4175)(-1650 4475);
WIRE 17 -1 (-1650 4025)(-1650 3925);
WIRE 17 -1 (-1650 3925)(-1650 3725);
WIRE 17 -1 (-1650 4475)(-1650 4575);
WIRE 17 -1 (-1650 4725)(-1650 4575);
WIRE 17 -1 (-1650 3725)(-1650 3525);
WIRE 17 -1 (-1650 5075)(-1650 4725);
WIRE 17 -1 (-1650 5075)(-3425 5075);
FORCEPROP 2 LAST SIG_NAME P3E_CPU1_PE3_MP_RXP<7:0>
J 0
(-3410 5085);
DISPLAY 0.617021 (-3410 5085);
PAINT ORANGE (-3410 5085);
WIRE 17 -1 (-1900 4075)(-1900 3875);
WIRE 17 -1 (-1900 4225)(-1900 4075);
WIRE 17 -1 (-1900 3875)(-1900 3675);
WIRE 17 -1 (-1900 3675)(-1900 3575);
WIRE 17 -1 (-1900 4225)(-1900 4425);
WIRE 17 -1 (-1900 4425)(-1900 4625);
WIRE 17 -1 (-1900 4775)(-1900 4625);
WIRE 17 -1 (-1900 4950)(-1900 4775);
WIRE 17 -1 (-1900 4950)(-3425 4950);
FORCEPROP 2 LAST SIG_NAME P3E_CPU1_PE3_MP_RXN<7:0>
J 0
(-3410 4960);
DISPLAY 0.617021 (-3410 4960);
PAINT ORANGE (-3410 4960);
WIRE 17 -1 (1750 3425)(1750 3125);
WIRE 17 -1 (1750 3525)(1750 3425);
WIRE 17 -1 (1750 3125)(1750 2975);
WIRE 17 -1 (1750 2975)(1750 2825);
WIRE 17 -1 (1750 3675)(1750 3525);
WIRE 17 -1 (1750 3675)(1750 3925);
WIRE 17 -1 (1750 3925)(1750 4025);
WIRE 17 -1 (1750 4825)(1750 4025);
WIRE 17 -1 (3025 4825)(1750 4825);
FORCEPROP 2 LAST SIG_NAME P3E_CPU1_PE3_MP_TXP<7:0>
J 0
(2165 4835);
DISPLAY 0.617021 (2165 4835);
PAINT ORANGE (2165 4835);
WIRE 17 -1 (2000 3575)(2000 3375);
WIRE 17 -1 (2000 3725)(2000 3575);
WIRE 17 -1 (2000 3375)(2000 3175);
WIRE 17 -1 (2000 3175)(2000 3025);
WIRE 17 -1 (2000 3725)(2000 3875);
WIRE 17 -1 (2000 3875)(2000 4075);
WIRE 17 -1 (2000 3025)(2000 2875);
WIRE 17 -1 (2000 4075)(2000 4725);
WIRE 17 -1 (3025 4725)(2000 4725);
FORCEPROP 2 LAST SIG_NAME P3E_CPU1_PE3_MP_TXN<7:0>
J 0
(2165 4735);
DISPLAY 0.617021 (2165 4735);
PAINT ORANGE (2165 4735);
WIRE 16 -1 (-1125 4650)(-1350 4650);
WIRE 16 -1 (-1350 4650)(-1350 4500);
WIRE 16 -1 (-1350 4500)(-1125 4500);
WIRE 16 -1 (-1350 4500)(-1350 4350);
WIRE 16 -1 (-1350 4350)(-1125 4350);
WIRE 16 -1 (-1350 4350)(-1350 4250);
WIRE 16 -1 (-1350 4250)(-1125 4250);
WIRE 16 -1 (-1350 4250)(-1350 4100);
WIRE 16 -1 (-1350 4100)(-1125 4100);
WIRE 16 -1 (-1350 4100)(-1350 3950);
WIRE 16 -1 (-1350 3950)(-1125 3950);
WIRE 16 -1 (-1350 3950)(-1350 3800);
WIRE 16 -1 (-1125 3800)(-1350 3800);
WIRE 16 -1 (-1350 3800)(-1350 3600);
WIRE 16 -1 (-1350 3600)(-1125 3600);
WIRE 16 -1 (-1350 3600)(-1350 3450);
WIRE 16 -1 (-1350 3450)(-1125 3450);
WIRE 16 -1 (-1350 2900)(-1350 3450);
WIRE 16 -1 (-1350 2900)(-1125 2900);
WIRE 16 -1 (-1350 2900)(-1350 2750);
WIRE 16 -1 (-1350 2750)(-1125 2750);
WIRE 16 -1 (-1350 2750)(-1350 2475);
WIRE 16 -1 (-2600 2200)(-2600 2275);
WIRE 16 -1 (100 1700)(100 1575);
WIRE 16 -1 (450 2300)(450 2250);
WIRE 16 -1 (550 1700)(550 1550);
WIRE 16 -1 (3050 1250)(3300 1250);
WIRE 16 -1 (3050 1100)(3050 1250);
WIRE 16 -1 (1725 2125)(1950 2125);
WIRE 16 -1 (1725 2300)(1725 2125);
WIRE 16 -1 (1725 2300)(1950 2300);
WIRE 16 -1 (1725 2475)(1725 2300);
WIRE 16 -1 (1725 2575)(1725 2475);
WIRE 16 -1 (1725 2475)(1950 2475);
WIRE 16 -1 (-300 775)(-300 750);
WIRE 16 -1 (3300 1600)(3050 1600);
WIRE 16 -1 (3050 1800)(3050 1600);
WIRE 16 -1 (-3000 1225)(-3000 1375);
WIRE 16 -1 (-1525 1275)(-1525 1125);
WIRE 16 -1 (-1525 775)(-1525 925);
WIRE 16 -1 (50 4100)(50 4650);
WIRE 16 -1 (50 3950)(50 4100);
WIRE 16 -1 (50 4100)(-125 4100);
WIRE 16 -1 (50 4650)(-125 4650);
WIRE 16 -1 (50 3800)(50 3950);
WIRE 16 -1 (50 3950)(-125 3950);
WIRE 16 -1 (50 3600)(50 3800);
WIRE 16 -1 (50 3800)(-125 3800);
WIRE 16 -1 (50 3450)(50 3600);
WIRE 16 -1 (50 3600)(-125 3600);
WIRE 16 -1 (50 3300)(50 3450);
WIRE 16 -1 (50 3450)(-125 3450);
WIRE 16 -1 (50 3200)(50 3300);
WIRE 16 -1 (50 3300)(-125 3300);
WIRE 16 -1 (50 3050)(50 3200);
WIRE 16 -1 (50 3200)(-125 3200);
WIRE 16 -1 (50 2900)(50 3050);
WIRE 16 -1 (50 3050)(-125 3050);
WIRE 16 -1 (50 2750)(50 2900);
WIRE 16 -1 (50 2900)(-125 2900);
WIRE 16 -1 (50 2425)(50 2750);
WIRE 16 -1 (50 2750)(-125 2750);
WIRE 3 2175 (-2975 4200)(-1950 4200);
WIRE 3 2175 (-2975 4200)(-2975 3275);
WIRE 3 2175 (-1950 4200)(-1950 3275);
WIRE 3 2175 (-2975 3275)(-1950 3275);
WIRE 16 -1 (-3425 2425)(-1525 2425);
FORCEPROP 2 LAST SIG_NAME FAN_PWM_OUT_SYS0_R1
J 0
(-3310 2435);
DISPLAY 0.617021 (-3310 2435);
PAINT ORANGE (-3310 2435);
WIRE 16 -1 (-1525 2425)(-1525 2950);
WIRE 16 -1 (-1125 2950)(-1525 2950);
WIRE 16 -1 (-1525 2950)(-2000 2950);
WIRE 16 -1 (-1125 2800)(-2550 2800);
FORCEPROP 0 LAST SIG_NAME CLK_100M_AIRMAX8_PE1_DN
J 0
(-2510 2810);
DISPLAY 0.617021 (-2510 2810);
PAINT ORANGE (-2510 2810);
WIRE 16 -1 (650 2800)(1650 2800);
WIRE 16 -1 (-3425 2575)(-1675 2575);
FORCEPROP 2 LAST SIG_NAME FAN_TACH2_R
J 0
(-3310 2585);
DISPLAY 0.617021 (-3310 2585);
PAINT ORANGE (-3310 2585);
WIRE 16 -1 (-1675 2575)(-1675 3150);
WIRE 16 -1 (-1675 3150)(-1125 3150);
WIRE 16 -1 (-2725 3150)(-1675 3150);
WIRE 16 -1 (-3475 3200)(-2225 3200);
FORCEPROP 2 LAST SIG_NAME FAN_TACH3
J 0
(-3410 3210);
DISPLAY 0.617021 (-3410 3210);
PAINT ORANGE (-3410 3210);
WIRE 16 -1 (-125 3000)(950 3000);
FORCEPROP 2 LAST SIG_NAME P3E_CPU1_PE3_MP_C_TXN<1>
J 0
(65 3010);
DISPLAY 0.617021 (65 3010);
PAINT ORANGE (65 3010);
FORCEPROP 2 LASTPROP $XRERR UNIQUE?
J 0
(-175 3010);
DISPLAY 0.638298 (-175 3010);
PAINT MONO (-175 3010);
DISPLAY INVISIBLE (-175 3010);
WIRE 16 -1 (700 3500)(1650 3500);
WIRE 16 -1 (700 3850)(1900 3850);
WIRE 16 -1 (1125 3900)(1650 3900);
WIRE 16 -1 (1650 4000)(700 4000);
WIRE 16 -1 (1125 4050)(1900 4050);
WIRE 16 -1 (-2600 2000)(-2600 1800);
WIRE 16 -1 (-2600 1800)(-2375 1800);
WIRE 16 -1 (-2600 1800)(-3000 1800);
WIRE 16 -1 (-3000 1575)(-3000 1800);
WIRE 16 -1 (-3400 1800)(-3000 1800);
FORCEPROP 0 LAST SIG_NAME FM_MATED_IN_N
J 0
(-3310 1810);
DISPLAY 0.617021 (-3310 1810);
PAINT ORANGE (-3310 1810);
WIRE 16 -1 (-2175 1800)(-1125 1800);
FORCEPROP 0 LAST SIG_NAME FM_MATED_IN_D1_N
J 0
(-1835 1810);
DISPLAY 0.617021 (-1835 1810);
PAINT ORANGE (-1835 1810);
FORCEPROP 2 LASTPROP $XRERR UNIQUE?
J 0
(-2075 1810);
DISPLAY 0.638298 (-2075 1810);
PAINT MONO (-2075 1810);
DISPLAY INVISIBLE (-2075 1810);
WIRE 16 -1 (-1125 3300)(-2925 3300);
FORCEPROP 0 LAST SIG_NAME FM_ENABLE_FAN_POWER
J 0
(-1910 3310);
DISPLAY 0.617021 (-1910 3310);
PAINT ORANGE (-1910 3310);
WIRE 16 -1 (-2600 3350)(-1125 3350);
FORCEPROP 0 LAST SIG_NAME SPA_MID_DBG_RX_R
J 0
(-1835 3360);
DISPLAY 0.617021 (-1835 3360);
PAINT ORANGE (-1835 3360);
FORCEPROP 2 LASTPROP $XRERR UNIQUE?
J 0
(-2075 3360);
DISPLAY 0.638298 (-2075 3360);
PAINT MONO (-2075 3360);
DISPLAY INVISIBLE (-2075 3360);
WIRE 16 -1 (-2600 3800)(-2600 3350);
WIRE 16 -1 (-2625 3350)(-2600 3350);
WIRE 16 -1 (-2675 3800)(-2600 3800);
WIRE 16 -1 (-1125 3100)(-1625 3100);
WIRE 16 -1 (-1625 3100)(-2025 3100);
WIRE 16 -1 (-1625 2525)(-1625 3100);
WIRE 16 -1 (-3425 2525)(-1625 2525);
FORCEPROP 2 LAST SIG_NAME FAN_TACH1_R
J 0
(-3310 2535);
DISPLAY 0.617021 (-3310 2535);
PAINT ORANGE (-3310 2535);
WIRE 16 -1 (-1575 3050)(-1125 3050);
WIRE 16 -1 (-1575 2475)(-1575 3050);
WIRE 16 -1 (-2725 3050)(-1575 3050);
WIRE 16 -1 (-3425 2475)(-1575 2475);
FORCEPROP 2 LAST SIG_NAME FAN_TACH0_R
J 0
(-3310 2485);
DISPLAY 0.617021 (-3310 2485);
PAINT ORANGE (-3310 2485);
WIRE 3 2175 (-3350 925)(-2525 925);
WIRE 3 2175 (-3350 1600)(-3350 925);
WIRE 3 2175 (-2525 1600)(-2525 925);
WIRE 3 2175 (-3350 1600)(-2525 1600);
WIRE 16 -1 (-1125 2850)(-2550 2850);
FORCEPROP 0 LAST SIG_NAME CLK_100M_AIRMAX8_PE1_DP
J 0
(-2510 2860);
DISPLAY 0.617021 (-2510 2860);
PAINT ORANGE (-2510 2860);
WIRE 16 -1 (-3450 2950)(-2200 2950);
FORCEPROP 2 LAST SIG_NAME FAN_PWM_OUT_SYS0_R
J 0
(-3385 2960);
DISPLAY 0.617021 (-3385 2960);
PAINT ORANGE (-3385 2960);
WIRE 16 -1 (-2550 3000)(-1125 3000);
FORCEPROP 0 LAST SIG_NAME FM_MATED_IN_N
J 0
(-2510 3010);
DISPLAY 0.617021 (-2510 3010);
PAINT ORANGE (-2510 3010);
WIRE 16 -1 (-3675 3800)(-2875 3800);
FORCEPROP 2 LAST SIG_NAME SP2_BMC_CM_UART_TX_R1
J 0
(-3635 3810);
DISPLAY 0.617021 (-3635 3810);
PAINT ORANGE (-3635 3810);
WIRE 16 -1 (-3475 3050)(-2925 3050);
FORCEPROP 2 LAST SIG_NAME FAN_TACH0
J 0
(-3410 3060);
DISPLAY 0.617021 (-3410 3060);
PAINT ORANGE (-3410 3060);
WIRE 16 -1 (-3425 2625)(-1725 2625);
FORCEPROP 2 LAST SIG_NAME FAN_TACH3_R
J 0
(-3310 2635);
DISPLAY 0.617021 (-3310 2635);
PAINT ORANGE (-3310 2635);
WIRE 16 -1 (-1725 2625)(-1725 3200);
WIRE 16 -1 (-1725 3200)(-1125 3200);
WIRE 16 -1 (-2025 3200)(-1725 3200);
WIRE 16 -1 (-3475 3100)(-2225 3100);
FORCEPROP 2 LAST SIG_NAME FAN_TACH1
J 0
(-3410 3110);
DISPLAY 0.617021 (-3410 3110);
PAINT ORANGE (-3410 3110);
WIRE 16 -1 (-1125 3400)(-2050 3400);
FORCEPROP 0 LAST SIG_NAME SPA_MID_DBG_TX_R
J 0
(-1835 3410);
DISPLAY 0.617021 (-1835 3410);
PAINT ORANGE (-1835 3410);
FORCEPROP 2 LASTPROP $XRERR UNIQUE?
J 0
(-2075 3410);
DISPLAY 0.638298 (-2075 3410);
PAINT MONO (-2075 3410);
DISPLAY INVISIBLE (-2075 3410);
WIRE 16 -1 (-2050 3850)(-2050 3400);
WIRE 16 -1 (-2050 3400)(-2250 3400);
WIRE 16 -1 (-2275 3850)(-2050 3850);
WIRE 16 -1 (-1125 4400)(-1800 4400);
WIRE 16 -1 (-3650 3400)(-2450 3400);
FORCEPROP 2 LAST SIG_NAME SPA_MID_DBG_TX
J 0
(-3610 3410);
DISPLAY 0.617021 (-3610 3410);
PAINT ORANGE (-3610 3410);
WIRE 16 -1 (-3650 3350)(-2825 3350);
FORCEPROP 2 LAST SIG_NAME SPA_MID_DBG_RX
J 0
(-3610 3360);
DISPLAY 0.617021 (-3610 3360);
PAINT ORANGE (-3610 3360);
WIRE 16 -1 (-3675 3850)(-2475 3850);
FORCEPROP 2 LAST SIG_NAME SP2_BMC_CM_UART_RX_R1
J 0
(-3635 3860);
DISPLAY 0.617021 (-3635 3860);
PAINT ORANGE (-3635 3860);
WIRE 16 -1 (-3475 3150)(-2925 3150);
FORCEPROP 2 LAST SIG_NAME FAN_TACH2
J 0
(-3410 3160);
DISPLAY 0.617021 (-3410 3160);
PAINT ORANGE (-3410 3160);
WIRE 16 -1 (-1125 4450)(-1550 4450);
WIRE 16 -1 (-300 975)(-300 1125);
FORCEPROP 0 LAST SIG_NAME FM_PS_EN
J 0
(-510 1135);
DISPLAY 0.617021 (-510 1135);
PAINT ORANGE (-510 1135);
WIRE 16 -1 (-300 1125)(100 1125);
WIRE 16 -1 (-550 1125)(-300 1125);
WIRE 16 -1 (2625 2125)(2150 2125);
FORCEPROP 0 LAST SIG_NAME FM_MB_SLOT_ID2
J 0
(2315 2135);
DISPLAY 0.617021 (2315 2135);
PAINT ORANGE (2315 2135);
WIRE 16 -1 (2625 2300)(2150 2300);
FORCEPROP 0 LAST SIG_NAME FM_MB_SLOT_ID1
J 0
(2315 2310);
DISPLAY 0.617021 (2315 2310);
PAINT ORANGE (2315 2310);
WIRE 16 -1 (2150 2475)(2625 2475);
FORCEPROP 0 LAST SIG_NAME FM_MB_SLOT_ID0
J 0
(2315 2485);
DISPLAY 0.617021 (2315 2485);
PAINT ORANGE (2315 2485);
WIRE 16 -1 (3300 1450)(2350 1450);
FORCEPROP 0 LAST SIG_NAME FM_MATED_IN_N
J 0
(2350 1460);
DISPLAY 0.617021 (2350 1460);
PAINT ORANGE (2350 1460);
WIRE 16 -1 (3300 1400)(2325 1400);
FORCEPROP 0 LAST SIG_NAME IRQ_SML1_PMBUS_ALERT_R_N
J 0
(2365 1410);
DISPLAY 0.617021 (2365 1410);
PAINT ORANGE (2365 1410);
WIRE 16 -1 (2350 1300)(3300 1300);
FORCEPROP 0 LAST SIG_NAME SMB_BMC_PMBUS_STBY_LVC3_SCL
J 0
(2365 1310);
DISPLAY 0.617021 (2365 1310);
PAINT ORANGE (2365 1310);
WIRE 16 -1 (3300 1350)(2350 1350);
FORCEPROP 0 LAST SIG_NAME SMB_BMC_PMBUS_STBY_LVC3_SDA
J 0
(2365 1360);
DISPLAY 0.617021 (2365 1360);
PAINT ORANGE (2365 1360);
WIRE 16 -1 (2350 1500)(3300 1500);
FORCEPROP 2 LAST SIG_NAME FM_MP_PS_FAIL_N
J 0
(2350 1510);
DISPLAY 0.617021 (2350 1510);
PAINT ORANGE (2350 1510);
WIRE 16 -1 (2350 1550)(3300 1550);
FORCEPROP 2 LAST SIG_NAME FM_MP_PS_REDUNDANT_LOST_N
J 0
(2350 1560);
DISPLAY 0.617021 (2350 1560);
PAINT ORANGE (2350 1560);
WIRE 16 -1 (1125 3700)(1900 3700);
WIRE 16 -1 (1150 3400)(1650 3400);
WIRE 16 -1 (1150 3550)(1900 3550);
WIRE 16 -1 (1900 3150)(1150 3150);
WIRE 16 -1 (1150 2850)(1900 2850);
WIRE 16 -1 (1150 3000)(1900 3000);
WIRE 16 -1 (650 2950)(1650 2950);
WIRE 16 -1 (1650 3650)(700 3650);
WIRE 16 -1 (700 3350)(1900 3350);
WIRE 16 -1 (650 3100)(1650 3100);
WIRE 16 -1 (550 2000)(1125 2000);
FORCEPROP 0 LAST SIG_NAME FM_P12V_HOTSWAP0_EN
J 0
(665 2010);
DISPLAY 0.617021 (665 2010);
PAINT ORANGE (665 2010);
WIRE 16 -1 (550 2000)(550 1900);
WIRE 16 -1 (450 2000)(550 2000);
WIRE 16 -1 (450 2050)(450 2000);
WIRE 16 -1 (450 2000)(100 2000);
WIRE 16 -1 (100 1900)(100 2000);
WIRE 16 -1 (1675 1075)(1150 1075);
FORCEPROP 0 LAST SIG_NAME FM_CTNR_PS_ON
J 0
(1290 1085);
DISPLAY 0.617021 (1290 1085);
PAINT ORANGE (1290 1085);
WIRE 16 -1 (400 1075)(950 1075);
FORCEPROP 0 LAST SIG_NAME FM_CTNR_PS_ON_R
J 0
(465 1085);
DISPLAY 0.617021 (465 1085);
PAINT ORANGE (465 1085);
FORCEPROP 2 LASTPROP $XRERR UNIQUE?
J 0
(225 1085);
DISPLAY 0.638298 (225 1085);
PAINT MONO (225 1085);
DISPLAY INVISIBLE (225 1085);
WIRE 16 -1 (-125 3900)(925 3900);
FORCEPROP 2 LAST SIG_NAME P3E_CPU1_PE3_MP_C_TXP<7>
J 0
(65 3910);
DISPLAY 0.617021 (65 3910);
PAINT ORANGE (65 3910);
FORCEPROP 2 LASTPROP $XRERR UNIQUE?
J 0
(-175 3910);
DISPLAY 0.638298 (-175 3910);
PAINT MONO (-175 3910);
DISPLAY INVISIBLE (-175 3910);
WIRE 16 -1 (-125 3850)(500 3850);
FORCEPROP 2 LAST SIG_NAME P3E_CPU1_PE3_MP_C_TXN<7>
J 0
(65 3860);
DISPLAY 0.617021 (65 3860);
PAINT ORANGE (65 3860);
FORCEPROP 2 LASTPROP $XRERR UNIQUE?
J 0
(-175 3860);
DISPLAY 0.638298 (-175 3860);
PAINT MONO (-175 3860);
DISPLAY INVISIBLE (-175 3860);
WIRE 16 -1 (-125 3700)(925 3700);
FORCEPROP 2 LAST SIG_NAME P3E_CPU1_PE3_MP_C_TXN<3>
J 0
(65 3710);
DISPLAY 0.617021 (65 3710);
PAINT ORANGE (65 3710);
FORCEPROP 2 LASTPROP $XRERR UNIQUE?
J 0
(-175 3710);
DISPLAY 0.638298 (-175 3710);
PAINT MONO (-175 3710);
DISPLAY INVISIBLE (-175 3710);
WIRE 16 -1 (-125 3550)(950 3550);
FORCEPROP 2 LAST SIG_NAME P3E_CPU1_PE3_MP_C_TXN<4>
J 0
(65 3560);
DISPLAY 0.617021 (65 3560);
PAINT ORANGE (65 3560);
FORCEPROP 2 LASTPROP $XRERR UNIQUE?
J 0
(-175 3560);
DISPLAY 0.638298 (-175 3560);
PAINT MONO (-175 3560);
DISPLAY INVISIBLE (-175 3560);
WIRE 16 -1 (-125 3500)(500 3500);
FORCEPROP 2 LAST SIG_NAME P3E_CPU1_PE3_MP_C_TXP<4>
J 0
(65 3510);
DISPLAY 0.617021 (65 3510);
PAINT ORANGE (65 3510);
FORCEPROP 2 LASTPROP $XRERR UNIQUE?
J 0
(-175 3510);
DISPLAY 0.638298 (-175 3510);
PAINT MONO (-175 3510);
DISPLAY INVISIBLE (-175 3510);
WIRE 16 -1 (-125 3100)(450 3100);
FORCEPROP 2 LAST SIG_NAME P3E_CPU1_PE3_MP_C_TXP<0>
J 0
(65 3110);
DISPLAY 0.617021 (65 3110);
PAINT ORANGE (65 3110);
FORCEPROP 2 LASTPROP $XRERR UNIQUE?
J 0
(-175 3110);
DISPLAY 0.638298 (-175 3110);
PAINT MONO (-175 3110);
DISPLAY INVISIBLE (-175 3110);
WIRE 16 -1 (-125 2950)(450 2950);
FORCEPROP 2 LAST SIG_NAME P3E_CPU1_PE3_MP_C_TXP<1>
J 0
(65 2960);
DISPLAY 0.617021 (65 2960);
PAINT ORANGE (65 2960);
FORCEPROP 2 LASTPROP $XRERR UNIQUE?
J 0
(-175 2960);
DISPLAY 0.638298 (-175 2960);
PAINT MONO (-175 2960);
DISPLAY INVISIBLE (-175 2960);
WIRE 16 -1 (-125 2850)(950 2850);
FORCEPROP 2 LAST SIG_NAME P3E_CPU1_PE3_MP_C_TXN<2>
J 0
(65 2860);
DISPLAY 0.617021 (65 2860);
PAINT ORANGE (65 2860);
FORCEPROP 2 LASTPROP $XRERR UNIQUE?
J 0
(-175 2860);
DISPLAY 0.638298 (-175 2860);
PAINT MONO (-175 2860);
DISPLAY INVISIBLE (-175 2860);
WIRE 16 -1 (950 3150)(-125 3150);
FORCEPROP 2 LAST SIG_NAME P3E_CPU1_PE3_MP_C_TXN<0>
J 0
(65 3160);
DISPLAY 0.617021 (65 3160);
PAINT ORANGE (65 3160);
FORCEPROP 2 LASTPROP $XRERR UNIQUE?
J 0
(-175 3160);
DISPLAY 0.638298 (-175 3160);
PAINT MONO (-175 3160);
DISPLAY INVISIBLE (-175 3160);
WIRE 16 -1 (-125 4050)(925 4050);
FORCEPROP 2 LAST SIG_NAME P3E_CPU1_PE3_MP_C_TXN<6>
J 0
(65 4060);
DISPLAY 0.617021 (65 4060);
PAINT ORANGE (65 4060);
FORCEPROP 2 LASTPROP $XRERR UNIQUE?
J 0
(-175 4060);
DISPLAY 0.638298 (-175 4060);
PAINT MONO (-175 4060);
DISPLAY INVISIBLE (-175 4060);
WIRE 16 -1 (-125 2800)(450 2800);
FORCEPROP 2 LAST SIG_NAME P3E_CPU1_PE3_MP_C_TXP<2>
J 0
(65 2810);
DISPLAY 0.617021 (65 2810);
PAINT ORANGE (65 2810);
FORCEPROP 2 LASTPROP $XRERR UNIQUE?
J 0
(-175 2810);
DISPLAY 0.638298 (-175 2810);
PAINT MONO (-175 2810);
DISPLAY INVISIBLE (-175 2810);
WIRE 16 -1 (500 4000)(-125 4000);
FORCEPROP 2 LAST SIG_NAME P3E_CPU1_PE3_MP_C_TXP<6>
J 0
(65 4010);
DISPLAY 0.617021 (65 4010);
PAINT ORANGE (65 4010);
FORCEPROP 2 LASTPROP $XRERR UNIQUE?
J 0
(-175 4010);
DISPLAY 0.638298 (-175 4010);
PAINT MONO (-175 4010);
DISPLAY INVISIBLE (-175 4010);
WIRE 16 -1 (500 3650)(-125 3650);
FORCEPROP 2 LAST SIG_NAME P3E_CPU1_PE3_MP_C_TXP<3>
J 0
(65 3660);
DISPLAY 0.617021 (65 3660);
PAINT ORANGE (65 3660);
FORCEPROP 2 LASTPROP $XRERR UNIQUE?
J 0
(-175 3660);
DISPLAY 0.638298 (-175 3660);
PAINT MONO (-175 3660);
DISPLAY INVISIBLE (-175 3660);
WIRE 16 -1 (-125 3350)(500 3350);
FORCEPROP 2 LAST SIG_NAME P3E_CPU1_PE3_MP_C_TXN<5>
J 0
(65 3360);
DISPLAY 0.617021 (65 3360);
PAINT ORANGE (65 3360);
FORCEPROP 2 LASTPROP $XRERR UNIQUE?
J 0
(-175 3360);
DISPLAY 0.638298 (-175 3360);
PAINT MONO (-175 3360);
DISPLAY INVISIBLE (-175 3360);
WIRE 16 -1 (-125 3400)(950 3400);
FORCEPROP 2 LAST SIG_NAME P3E_CPU1_PE3_MP_C_TXP<5>
J 0
(65 3410);
DISPLAY 0.617021 (65 3410);
PAINT ORANGE (65 3410);
FORCEPROP 2 LASTPROP $XRERR UNIQUE?
J 0
(-175 3410);
DISPLAY 0.638298 (-175 3410);
PAINT MONO (-175 3410);
DISPLAY INVISIBLE (-175 3410);
WIRE 16 -1 (-125 4750)(1100 4750);
FORCEPROP 2 LAST SIG_NAME NIC_MDI_MNG_TX_DP
J 0
(265 4760);
DISPLAY 0.617021 (265 4760);
PAINT ORANGE (265 4760);
WIRE 16 -1 (1100 4700)(-125 4700);
FORCEPROP 2 LAST SIG_NAME NIC_MDI_MNG_TX_DN
J 0
(265 4710);
DISPLAY 0.617021 (265 4710);
PAINT ORANGE (265 4710);
WIRE 16 -1 (-125 4600)(1100 4600);
FORCEPROP 2 LAST SIG_NAME NIC_MDI_MNG_RX_DP
J 0
(265 4610);
DISPLAY 0.617021 (265 4610);
PAINT ORANGE (265 4610);
WIRE 16 -1 (1100 4550)(-125 4550);
FORCEPROP 2 LAST SIG_NAME NIC_MDI_MNG_RX_DN
J 0
(265 4560);
DISPLAY 0.617021 (265 4560);
PAINT ORANGE (265 4560);
WIRE 16 -1 (1100 4350)(-125 4350);
FORCEPROP 2 LAST SIG_NAME RST_PCIE_MIDPLANE_N
J 0
(240 4360);
DISPLAY 0.617021 (240 4360);
PAINT ORANGE (240 4360);
WIRE 16 -1 (-125 4250)(1100 4250);
FORCEPROP 2 LAST SIG_NAME IRQ_SML1_PMBUS_ALERT_R_N
J 0
(240 4260);
DISPLAY 0.617021 (240 4260);
PAINT ORANGE (240 4260);
WIRE 16 -1 (-125 4150)(1100 4150);
FORCEPROP 2 LAST SIG_NAME SMB_BMC_PMBUS_STBY_LVC3_SCL
J 0
(240 4160);
DISPLAY 0.617021 (240 4160);
PAINT ORANGE (240 4160);
WIRE 16 -1 (-125 4200)(1100 4200);
FORCEPROP 2 LAST SIG_NAME SMB_BMC_PMBUS_STBY_LVC3_SDA
J 0
(240 4210);
DISPLAY 0.617021 (240 4210);
PAINT ORANGE (240 4210);
WIRE 16 -1 (100 1025)(-550 1025);
FORCEPROP 0 LAST SIG_NAME PWRGD_P12V_HSC_DLY
J 0
(-510 1035);
DISPLAY 0.617021 (-510 1035);
PAINT ORANGE (-510 1035);
WIRE 16 -1 (-125 4500)(1100 4500);
FORCEPROP 2 LAST SIG_NAME FM_MB_SLOT_ID0
J 0
(465 4510);
DISPLAY 0.617021 (465 4510);
PAINT ORANGE (465 4510);
WIRE 16 -1 (-125 4450)(1100 4450);
FORCEPROP 2 LAST SIG_NAME FM_MB_SLOT_ID1
J 0
(465 4460);
DISPLAY 0.617021 (465 4460);
PAINT ORANGE (465 4460);
WIRE 16 -1 (1100 4400)(-125 4400);
FORCEPROP 2 LAST SIG_NAME FM_MB_SLOT_ID2
J 0
(465 4410);
DISPLAY 0.617021 (465 4410);
PAINT ORANGE (465 4410);
WIRE 16 -1 (-1125 4150)(-1550 4150);
WIRE 16 -1 (-1125 4550)(-1550 4550);
WIRE 16 -1 (-1125 4700)(-1550 4700);
WIRE 16 -1 (-1125 4750)(-1800 4750);
WIRE 16 -1 (-1125 4600)(-1800 4600);
WIRE 16 -1 (-1125 4200)(-1800 4200);
WIRE 16 -1 (-1125 3550)(-1800 3550);
WIRE 16 -1 (-1125 4050)(-1800 4050);
WIRE 16 -1 (-1125 3500)(-1550 3500);
WIRE 16 -1 (-1125 3700)(-1550 3700);
WIRE 16 -1 (-1125 3650)(-1800 3650);
WIRE 16 -1 (-1125 3900)(-1550 3900);
WIRE 16 -1 (-1125 3850)(-1800 3850);
WIRE 16 -1 (-1125 4000)(-1550 4000);
WIRE 16 -1 (-925 1800)(-50 1800);
FORCEPROP 0 LAST SIG_NAME FM_MATED_IN_D2_N
J 0
(-760 1810);
DISPLAY 0.617021 (-760 1810);
PAINT ORANGE (-760 1810);
FORCEPROP 2 LASTPROP $XRERR UNIQUE?
J 0
(-1000 1810);
DISPLAY 0.638298 (-1000 1810);
PAINT MONO (-1000 1810);
DISPLAY INVISIBLE (-1000 1810);
DOT 1 (-2600 1800);
DOT 1 (-3000 1800);
DOT 1 (-2600 3350);
DOT 1 (-2050 3400);
DOT 1 (-300 1125);
DOT 1 (-1525 2950);
DOT 1 (-1350 2750);
DOT 1 (-1350 2900);
DOT 1 (-1675 3150);
DOT 1 (-1350 3450);
DOT 1 (-1350 3600);
DOT 1 (-1350 3800);
DOT 1 (-1350 3950);
DOT 1 (-1350 4100);
DOT 1 (-1350 4250);
DOT 1 (-1350 4350);
DOT 1 (-1350 4500);
DOT 1 (450 2000);
DOT 1 (550 2000);
DOT 1 (50 2750);
DOT 1 (50 3050);
DOT 1 (50 2900);
DOT 1 (50 3300);
DOT 1 (50 3200);
DOT 1 (50 3450);
DOT 1 (50 3600);
DOT 1 (50 3800);
DOT 1 (50 3950);
DOT 1 (1725 2300);
DOT 1 (1725 2475);
DOT 1 (50 4100);
DOT 1 (-1725 3200);
DOT 1 (-1575 3050);
DOT 1 (-1625 3100);
FORCENOTE
TP FAB1 POP 0OHM 1120
(-3325 975) 0;
DISPLAY LEFT (-3325 975);
DISPLAY 1.021277 (-3325 975);
PAINT RED (-3325 975);
FORCENOTE
BOM_COST:IO_SLOT
(-3875 700) 0;
DISPLAY LEFT (-3875 700);
DISPLAY 1.021277 (-3875 700);
PAINT PURPLE (-3875 700);
FORCENOTE
ROOM: IO_SLOT
(-3875 750) 0;
DISPLAY LEFT (-3875 750);
DISPLAY 1.021277 (-3875 750);
PAINT PURPLE (-3875 750);
FORCENOTE
TP FAB1 POP R9F64 R9F67
(-2950 4100) 0;
DISPLAY LEFT (-2950 4100);
DISPLAY 1.021277 (-2950 4100);
PAINT RED (-2950 4100);
FORCENOTE
NOPOP R9F63,R9F70 1123
(-2700 4025) 0;
DISPLAY LEFT (-2700 4025);
DISPLAY 1.021277 (-2700 4025);
PAINT RED (-2700 4025);
QUIT
